(kicad_sch
	(version 20250114)
	(generator "eeschema")
	(generator_version "9.0")
	(paper "A3")
	(title_block
		(title "OCuLink to 10GbE adapter")
		(date "2026-02-23")
		(rev "1.1.0")
		(company "Antmicro Ltd")
		(comment 1 "www.antmicro.com")
	)
	(rectangle
		(start 250.444 26.67)
		(end 272.034 33.02)
		(stroke
			(width 0)
			(type default)
		)
		(fill
			(type none)
		)
	)
	(text "Close switch to\nenable debug mode"
		(exclude_from_sim no)
		(at 251.46 31.75 0)
		(effects
			(font
				(size 1.27 1.27)
			)
			(justify left bottom)
		)
	)
	(text "X710-AT2 Reserved Pins"
		(exclude_from_sim no)
		(at 215.9 25.4 0)
		(effects
			(font
				(size 2.54 2.54)
				(thickness 0.508)
				(bold yes)
			)
		)
	)
	(junction
		(at 193.04 196.85)
		(diameter 0)
		(color 0 0 0 0)
	)
	(junction
		(at 193.04 217.17)
		(diameter 0)
		(color 0 0 0 0)
	)
	(junction
		(at 276.86 49.53)
		(diameter 0)
		(color 0 0 0 0)
	)
	(junction
		(at 193.04 214.63)
		(diameter 0)
		(color 0 0 0 0)
	)
	(junction
		(at 193.04 219.71)
		(diameter 0)
		(color 0 0 0 0)
	)
	(junction
		(at 193.04 189.23)
		(diameter 0)
		(color 0 0 0 0)
	)
	(junction
		(at 269.24 52.07)
		(diameter 0)
		(color 0 0 0 0)
	)
	(junction
		(at 173.99 168.91)
		(diameter 0)
		(color 0 0 0 0)
	)
	(junction
		(at 193.04 212.09)
		(diameter 0)
		(color 0 0 0 0)
	)
	(junction
		(at 193.04 207.01)
		(diameter 0)
		(color 0 0 0 0)
	)
	(junction
		(at 193.04 199.39)
		(diameter 0)
		(color 0 0 0 0)
	)
	(junction
		(at 241.3 232.41)
		(diameter 0)
		(color 0 0 0 0)
	)
	(junction
		(at 241.3 229.87)
		(diameter 0)
		(color 0 0 0 0)
	)
	(junction
		(at 193.04 201.93)
		(diameter 0)
		(color 0 0 0 0)
	)
	(junction
		(at 261.62 54.61)
		(diameter 0)
		(color 0 0 0 0)
	)
	(junction
		(at 276.86 39.37)
		(diameter 0)
		(color 0 0 0 0)
	)
	(junction
		(at 269.24 39.37)
		(diameter 0)
		(color 0 0 0 0)
	)
	(junction
		(at 193.04 186.69)
		(diameter 0)
		(color 0 0 0 0)
	)
	(junction
		(at 193.04 209.55)
		(diameter 0)
		(color 0 0 0 0)
	)
	(junction
		(at 193.04 194.31)
		(diameter 0)
		(color 0 0 0 0)
	)
	(junction
		(at 193.04 204.47)
		(diameter 0)
		(color 0 0 0 0)
	)
	(junction
		(at 193.04 191.77)
		(diameter 0)
		(color 0 0 0 0)
	)
	(no_connect
		(at 238.76 212.09)
	)
	(no_connect
		(at 238.76 135.89)
	)
	(no_connect
		(at 238.76 237.49)
	)
	(no_connect
		(at 195.58 88.9)
	)
	(no_connect
		(at 195.58 81.28)
	)
	(no_connect
		(at 238.76 120.65)
	)
	(no_connect
		(at 238.76 110.49)
	)
	(no_connect
		(at 238.76 62.23)
	)
	(no_connect
		(at 238.76 214.63)
	)
	(no_connect
		(at 238.76 118.11)
	)
	(no_connect
		(at 238.76 97.79)
	)
	(no_connect
		(at 195.58 86.36)
	)
	(no_connect
		(at 238.76 67.31)
	)
	(no_connect
		(at 195.58 245.11)
	)
	(no_connect
		(at 238.76 77.47)
	)
	(no_connect
		(at 195.58 247.65)
	)
	(no_connect
		(at 195.58 229.87)
	)
	(no_connect
		(at 238.76 125.73)
	)
	(no_connect
		(at 238.76 105.41)
	)
	(no_connect
		(at 195.58 227.33)
	)
	(no_connect
		(at 238.76 140.97)
	)
	(no_connect
		(at 238.76 69.85)
	)
	(no_connect
		(at 195.58 240.03)
	)
	(no_connect
		(at 238.76 113.03)
	)
	(no_connect
		(at 238.76 123.19)
	)
	(no_connect
		(at 238.76 92.71)
	)
	(no_connect
		(at 238.76 59.69)
	)
	(no_connect
		(at 238.76 85.09)
	)
	(no_connect
		(at 238.76 95.25)
	)
	(no_connect
		(at 238.76 64.77)
	)
	(no_connect
		(at 195.58 237.49)
	)
	(no_connect
		(at 195.58 224.79)
	)
	(no_connect
		(at 238.76 196.85)
	)
	(no_connect
		(at 238.76 219.71)
	)
	(no_connect
		(at 238.76 87.63)
	)
	(no_connect
		(at 238.76 207.01)
	)
	(no_connect
		(at 238.76 82.55)
	)
	(no_connect
		(at 238.76 74.93)
	)
	(no_connect
		(at 238.76 199.39)
	)
	(no_connect
		(at 238.76 72.39)
	)
	(no_connect
		(at 238.76 181.61)
	)
	(no_connect
		(at 238.76 179.07)
	)
	(no_connect
		(at 238.76 184.15)
	)
	(no_connect
		(at 238.76 191.77)
	)
	(no_connect
		(at 195.58 83.82)
	)
	(no_connect
		(at 238.76 100.33)
	)
	(no_connect
		(at 195.58 232.41)
	)
	(no_connect
		(at 238.76 194.31)
	)
	(no_connect
		(at 238.76 209.55)
	)
	(no_connect
		(at 238.76 128.27)
	)
	(no_connect
		(at 238.76 133.35)
	)
	(no_connect
		(at 238.76 115.57)
	)
	(no_connect
		(at 238.76 102.87)
	)
	(no_connect
		(at 238.76 234.95)
	)
	(no_connect
		(at 238.76 201.93)
	)
	(no_connect
		(at 238.76 130.81)
	)
	(no_connect
		(at 238.76 189.23)
	)
	(no_connect
		(at 238.76 80.01)
	)
	(no_connect
		(at 238.76 90.17)
	)
	(no_connect
		(at 238.76 107.95)
	)
	(no_connect
		(at 238.76 204.47)
	)
	(no_connect
		(at 238.76 138.43)
	)
	(no_connect
		(at 238.76 217.17)
	)
	(no_connect
		(at 238.76 186.69)
	)
	(wire
		(pts
			(xy 153.67 64.77) (xy 195.58 64.77)
		)
		(stroke
			(width 0)
			(type default)
		)
	)
	(wire
		(pts
			(xy 193.04 219.71) (xy 195.58 219.71)
		)
		(stroke
			(width 0)
			(type default)
		)
	)
	(wire
		(pts
			(xy 127 76.2) (xy 127 54.61)
		)
		(stroke
			(width 0)
			(type default)
		)
	)
	(wire
		(pts
			(xy 180.34 73.66) (xy 195.58 73.66)
		)
		(stroke
			(width 0)
			(type default)
		)
	)
	(wire
		(pts
			(xy 261.62 39.37) (xy 269.24 39.37)
		)
		(stroke
			(width 0)
			(type default)
		)
	)
	(wire
		(pts
			(xy 269.24 52.07) (xy 269.24 57.15)
		)
		(stroke
			(width 0)
			(type default)
		)
	)
	(wire
		(pts
			(xy 195.58 186.69) (xy 193.04 186.69)
		)
		(stroke
			(width 0)
			(type default)
		)
	)
	(wire
		(pts
			(xy 276.86 36.83) (xy 276.86 39.37)
		)
		(stroke
			(width 0)
			(type default)
		)
	)
	(wire
		(pts
			(xy 193.04 219.71) (xy 193.04 250.19)
		)
		(stroke
			(width 0)
			(type default)
		)
	)
	(wire
		(pts
			(xy 173.99 168.91) (xy 173.99 171.45)
		)
		(stroke
			(width 0)
			(type default)
		)
	)
	(wire
		(pts
			(xy 193.04 189.23) (xy 193.04 191.77)
		)
		(stroke
			(width 0)
			(type default)
		)
	)
	(wire
		(pts
			(xy 195.58 212.09) (xy 193.04 212.09)
		)
		(stroke
			(width 0)
			(type default)
		)
	)
	(wire
		(pts
			(xy 241.3 229.87) (xy 241.3 232.41)
		)
		(stroke
			(width 0)
			(type default)
		)
	)
	(wire
		(pts
			(xy 153.67 81.28) (xy 153.67 83.82)
		)
		(stroke
			(width 0)
			(type default)
		)
	)
	(wire
		(pts
			(xy 195.58 189.23) (xy 193.04 189.23)
		)
		(stroke
			(width 0)
			(type default)
		)
	)
	(wire
		(pts
			(xy 261.62 54.61) (xy 261.62 57.15)
		)
		(stroke
			(width 0)
			(type default)
		)
	)
	(wire
		(pts
			(xy 193.04 184.15) (xy 193.04 186.69)
		)
		(stroke
			(width 0)
			(type default)
		)
	)
	(wire
		(pts
			(xy 269.24 39.37) (xy 276.86 39.37)
		)
		(stroke
			(width 0)
			(type default)
		)
	)
	(wire
		(pts
			(xy 166.37 168.91) (xy 166.37 171.45)
		)
		(stroke
			(width 0)
			(type default)
		)
	)
	(wire
		(pts
			(xy 238.76 52.07) (xy 269.24 52.07)
		)
		(stroke
			(width 0)
			(type default)
		)
	)
	(wire
		(pts
			(xy 276.86 46.99) (xy 276.86 49.53)
		)
		(stroke
			(width 0)
			(type default)
		)
	)
	(wire
		(pts
			(xy 193.04 201.93) (xy 193.04 204.47)
		)
		(stroke
			(width 0)
			(type default)
		)
	)
	(wire
		(pts
			(xy 173.99 166.37) (xy 173.99 168.91)
		)
		(stroke
			(width 0)
			(type default)
		)
	)
	(wire
		(pts
			(xy 269.24 62.23) (xy 269.24 64.77)
		)
		(stroke
			(width 0)
			(type default)
		)
	)
	(wire
		(pts
			(xy 171.45 81.28) (xy 171.45 83.82)
		)
		(stroke
			(width 0)
			(type default)
		)
	)
	(wire
		(pts
			(xy 193.04 214.63) (xy 193.04 217.17)
		)
		(stroke
			(width 0)
			(type default)
		)
	)
	(wire
		(pts
			(xy 193.04 186.69) (xy 193.04 189.23)
		)
		(stroke
			(width 0)
			(type default)
		)
	)
	(wire
		(pts
			(xy 173.99 176.53) (xy 173.99 179.07)
		)
		(stroke
			(width 0)
			(type default)
		)
	)
	(wire
		(pts
			(xy 276.86 62.23) (xy 276.86 64.77)
		)
		(stroke
			(width 0)
			(type default)
		)
	)
	(wire
		(pts
			(xy 193.04 209.55) (xy 193.04 212.09)
		)
		(stroke
			(width 0)
			(type default)
		)
	)
	(wire
		(pts
			(xy 238.76 232.41) (xy 241.3 232.41)
		)
		(stroke
			(width 0)
			(type default)
		)
	)
	(wire
		(pts
			(xy 166.37 176.53) (xy 166.37 181.61)
		)
		(stroke
			(width 0)
			(type default)
		)
	)
	(wire
		(pts
			(xy 193.04 207.01) (xy 193.04 209.55)
		)
		(stroke
			(width 0)
			(type default)
		)
	)
	(wire
		(pts
			(xy 135.89 57.15) (xy 195.58 57.15)
		)
		(stroke
			(width 0)
			(type default)
		)
	)
	(wire
		(pts
			(xy 193.04 212.09) (xy 193.04 214.63)
		)
		(stroke
			(width 0)
			(type default)
		)
	)
	(wire
		(pts
			(xy 193.04 196.85) (xy 193.04 199.39)
		)
		(stroke
			(width 0)
			(type default)
		)
	)
	(wire
		(pts
			(xy 193.04 204.47) (xy 193.04 207.01)
		)
		(stroke
			(width 0)
			(type default)
		)
	)
	(wire
		(pts
			(xy 144.78 81.28) (xy 144.78 83.82)
		)
		(stroke
			(width 0)
			(type default)
		)
	)
	(wire
		(pts
			(xy 162.56 81.28) (xy 162.56 83.82)
		)
		(stroke
			(width 0)
			(type default)
		)
	)
	(wire
		(pts
			(xy 144.78 76.2) (xy 144.78 62.23)
		)
		(stroke
			(width 0)
			(type default)
		)
	)
	(wire
		(pts
			(xy 238.76 54.61) (xy 261.62 54.61)
		)
		(stroke
			(width 0)
			(type default)
		)
	)
	(wire
		(pts
			(xy 195.58 196.85) (xy 193.04 196.85)
		)
		(stroke
			(width 0)
			(type default)
		)
	)
	(wire
		(pts
			(xy 173.99 179.07) (xy 195.58 179.07)
		)
		(stroke
			(width 0)
			(type default)
		)
	)
	(wire
		(pts
			(xy 195.58 191.77) (xy 193.04 191.77)
		)
		(stroke
			(width 0)
			(type default)
		)
	)
	(wire
		(pts
			(xy 127 81.28) (xy 127 83.82)
		)
		(stroke
			(width 0)
			(type default)
		)
	)
	(wire
		(pts
			(xy 166.37 181.61) (xy 195.58 181.61)
		)
		(stroke
			(width 0)
			(type default)
		)
	)
	(wire
		(pts
			(xy 241.3 224.79) (xy 241.3 229.87)
		)
		(stroke
			(width 0)
			(type default)
		)
	)
	(wire
		(pts
			(xy 180.34 81.28) (xy 180.34 83.82)
		)
		(stroke
			(width 0)
			(type default)
		)
	)
	(wire
		(pts
			(xy 162.56 67.31) (xy 195.58 67.31)
		)
		(stroke
			(width 0)
			(type default)
		)
	)
	(wire
		(pts
			(xy 276.86 41.91) (xy 276.86 39.37)
		)
		(stroke
			(width 0)
			(type default)
		)
	)
	(wire
		(pts
			(xy 135.89 81.28) (xy 135.89 83.82)
		)
		(stroke
			(width 0)
			(type default)
		)
	)
	(wire
		(pts
			(xy 166.37 168.91) (xy 173.99 168.91)
		)
		(stroke
			(width 0)
			(type default)
		)
	)
	(wire
		(pts
			(xy 162.56 76.2) (xy 162.56 67.31)
		)
		(stroke
			(width 0)
			(type default)
		)
	)
	(wire
		(pts
			(xy 195.58 199.39) (xy 193.04 199.39)
		)
		(stroke
			(width 0)
			(type default)
		)
	)
	(wire
		(pts
			(xy 276.86 21.59) (xy 276.86 24.13)
		)
		(stroke
			(width 0)
			(type default)
		)
	)
	(wire
		(pts
			(xy 193.04 191.77) (xy 193.04 194.31)
		)
		(stroke
			(width 0)
			(type default)
		)
	)
	(wire
		(pts
			(xy 144.78 62.23) (xy 195.58 62.23)
		)
		(stroke
			(width 0)
			(type default)
		)
	)
	(wire
		(pts
			(xy 241.3 232.41) (xy 241.3 250.19)
		)
		(stroke
			(width 0)
			(type default)
		)
	)
	(wire
		(pts
			(xy 195.58 214.63) (xy 193.04 214.63)
		)
		(stroke
			(width 0)
			(type default)
		)
	)
	(wire
		(pts
			(xy 195.58 209.55) (xy 193.04 209.55)
		)
		(stroke
			(width 0)
			(type default)
		)
	)
	(wire
		(pts
			(xy 153.67 76.2) (xy 153.67 64.77)
		)
		(stroke
			(width 0)
			(type default)
		)
	)
	(wire
		(pts
			(xy 269.24 41.91) (xy 269.24 39.37)
		)
		(stroke
			(width 0)
			(type default)
		)
	)
	(wire
		(pts
			(xy 195.58 184.15) (xy 193.04 184.15)
		)
		(stroke
			(width 0)
			(type default)
		)
	)
	(wire
		(pts
			(xy 238.76 224.79) (xy 241.3 224.79)
		)
		(stroke
			(width 0)
			(type default)
		)
	)
	(wire
		(pts
			(xy 171.45 69.85) (xy 195.58 69.85)
		)
		(stroke
			(width 0)
			(type default)
		)
	)
	(wire
		(pts
			(xy 135.89 76.2) (xy 135.89 57.15)
		)
		(stroke
			(width 0)
			(type default)
		)
	)
	(wire
		(pts
			(xy 195.58 204.47) (xy 193.04 204.47)
		)
		(stroke
			(width 0)
			(type default)
		)
	)
	(wire
		(pts
			(xy 261.62 41.91) (xy 261.62 39.37)
		)
		(stroke
			(width 0)
			(type default)
		)
	)
	(wire
		(pts
			(xy 195.58 194.31) (xy 193.04 194.31)
		)
		(stroke
			(width 0)
			(type default)
		)
	)
	(wire
		(pts
			(xy 171.45 76.2) (xy 171.45 69.85)
		)
		(stroke
			(width 0)
			(type default)
		)
	)
	(wire
		(pts
			(xy 193.04 194.31) (xy 193.04 196.85)
		)
		(stroke
			(width 0)
			(type default)
		)
	)
	(wire
		(pts
			(xy 269.24 46.99) (xy 269.24 52.07)
		)
		(stroke
			(width 0)
			(type default)
		)
	)
	(wire
		(pts
			(xy 193.04 217.17) (xy 193.04 219.71)
		)
		(stroke
			(width 0)
			(type default)
		)
	)
	(wire
		(pts
			(xy 261.62 46.99) (xy 261.62 54.61)
		)
		(stroke
			(width 0)
			(type default)
		)
	)
	(wire
		(pts
			(xy 180.34 76.2) (xy 180.34 73.66)
		)
		(stroke
			(width 0)
			(type default)
		)
	)
	(wire
		(pts
			(xy 238.76 229.87) (xy 241.3 229.87)
		)
		(stroke
			(width 0)
			(type default)
		)
	)
	(wire
		(pts
			(xy 195.58 217.17) (xy 193.04 217.17)
		)
		(stroke
			(width 0)
			(type default)
		)
	)
	(wire
		(pts
			(xy 195.58 201.93) (xy 193.04 201.93)
		)
		(stroke
			(width 0)
			(type default)
		)
	)
	(wire
		(pts
			(xy 276.86 49.53) (xy 276.86 57.15)
		)
		(stroke
			(width 0)
			(type default)
		)
	)
	(wire
		(pts
			(xy 195.58 207.01) (xy 193.04 207.01)
		)
		(stroke
			(width 0)
			(type default)
		)
	)
	(wire
		(pts
			(xy 118.11 81.28) (xy 118.11 83.82)
		)
		(stroke
			(width 0)
			(type default)
		)
	)
	(wire
		(pts
			(xy 238.76 49.53) (xy 276.86 49.53)
		)
		(stroke
			(width 0)
			(type default)
		)
	)
	(wire
		(pts
			(xy 127 54.61) (xy 195.58 54.61)
		)
		(stroke
			(width 0)
			(type default)
		)
	)
	(wire
		(pts
			(xy 118.11 49.53) (xy 195.58 49.53)
		)
		(stroke
			(width 0)
			(type default)
		)
	)
	(wire
		(pts
			(xy 193.04 199.39) (xy 193.04 201.93)
		)
		(stroke
			(width 0)
			(type default)
		)
	)
	(wire
		(pts
			(xy 118.11 76.2) (xy 118.11 49.53)
		)
		(stroke
			(width 0)
			(type default)
		)
	)
	(wire
		(pts
			(xy 261.62 62.23) (xy 261.62 64.77)
		)
		(stroke
			(width 0)
			(type default)
		)
	)
	(label "DEBUG_EN"
		(at 261.62 39.37 0)
		(effects
			(font
				(size 1.27 1.27)
			)
			(justify left bottom)
		)
	)
	(label "RSVDN9_VSS"
		(at 193.04 62.23 180)
		(effects
			(font
				(size 1.27 1.27)
			)
			(justify right bottom)
		)
	)
	(label "RSVDP22_VSS"
		(at 193.04 67.31 180)
		(effects
			(font
				(size 1.27 1.27)
			)
			(justify right bottom)
		)
	)
	(label "DEBUG_W7"
		(at 241.3 52.07 0)
		(effects
			(font
				(size 1.27 1.27)
			)
			(justify left bottom)
		)
	)
	(label "RSVDY18_VSS"
		(at 193.04 69.85 180)
		(effects
			(font
				(size 1.27 1.27)
			)
			(justify right bottom)
		)
	)
	(label "RSVDY22_VSS"
		(at 193.04 54.61 180)
		(effects
			(font
				(size 1.27 1.27)
			)
			(justify right bottom)
		)
	)
	(label "DEBUG_Y20"
		(at 241.3 54.61 0)
		(effects
			(font
				(size 1.27 1.27)
			)
			(justify left bottom)
		)
	)
	(label "RSVDW1_VSS"
		(at 193.04 64.77 180)
		(effects
			(font
				(size 1.27 1.27)
			)
			(justify right bottom)
		)
	)
	(label "RSVDE19_1P88V"
		(at 193.04 179.07 180)
		(effects
			(font
				(size 1.27 1.27)
			)
			(justify right bottom)
		)
	)
	(label "RSVDW5_VSS"
		(at 193.04 57.15 180)
		(effects
			(font
				(size 1.27 1.27)
			)
			(justify right bottom)
		)
	)
	(label "RSVDY24_VSS"
		(at 193.04 49.53 180)
		(effects
			(font
				(size 1.27 1.27)
			)
			(justify right bottom)
		)
	)
	(label "DEBUG_Y16"
		(at 241.3 49.53 0)
		(effects
			(font
				(size 1.27 1.27)
			)
			(justify left bottom)
		)
	)
	(label "RSVDD8_1P88V"
		(at 193.04 181.61 180)
		(effects
			(font
				(size 1.27 1.27)
			)
			(justify right bottom)
		)
	)
	(label "RSVDP8_VSS"
		(at 193.04 73.66 180)
		(effects
			(font
				(size 1.27 1.27)
			)
			(justify right bottom)
		)
	)
	(symbol
		(lib_id "antmicroResistors0402:R_1k_0402")
		(at 166.37 176.53 90)
		(unit 1)
		(exclude_from_sim no)
		(in_bom yes)
		(on_board yes)
		(dnp no)
		(property "Reference" "R142"
			(at 167.894 172.72 90)
			(effects
				(font
					(size 1.27 1.27)
					(thickness 0.15)
				)
				(justify right)
			)
		)
		(property "Value" "R_1k_0402"
			(at 179.07 156.21 0)
			(effects
				(font
					(size 1.27 1.27)
					(thickness 0.15)
				)
				(justify left bottom)
				(hide yes)
			)
		)
		(property "Footprint" "antmicro-footprints:R_0402_1005Metric"
			(at 181.61 156.21 0)
			(effects
				(font
					(size 1.27 1.27)
					(thickness 0.15)
				)
				(justify left bottom)
				(hide yes)
			)
		)
		(property "Datasheet" "https://www.bourns.com/docs/product-datasheets/cr.pdf"
			(at 184.15 156.21 0)
			(effects
				(font
					(size 1.27 1.27)
					(thickness 0.15)
				)
				(justify left bottom)
				(hide yes)
			)
		)
		(property "Description" "SMD Chip Resistor, 1 kohm, ± 1%, 63 mW, 0402 [1005 Metric], Thick Film, General Purpose"
			(at 166.37 176.53 0)
			(effects
				(font
					(size 1.27 1.27)
				)
				(hide yes)
			)
		)
		(property "MPN" "CR0402-FX-1001GLF"
			(at 186.69 156.21 0)
			(effects
				(font
					(size 1.27 1.27)
					(thickness 0.15)
				)
				(justify left bottom)
				(hide yes)
			)
		)
		(property "Manufacturer" "Bourns"
			(at 189.23 156.21 0)
			(effects
				(font
					(size 1.27 1.27)
					(thickness 0.15)
				)
				(justify left bottom)
				(hide yes)
			)
		)
		(property "License" "Apache-2.0"
			(at 191.77 156.21 0)
			(effects
				(font
					(size 1.27 1.27)
					(thickness 0.15)
				)
				(justify left bottom)
				(hide yes)
			)
		)
		(property "Author" "Antmicro"
			(at 194.31 156.21 0)
			(effects
				(font
					(size 1.27 1.27)
					(thickness 0.15)
				)
				(justify left bottom)
				(hide yes)
			)
		)
		(property "Val" "1k"
			(at 167.894 175.26 90)
			(effects
				(font
					(size 1.27 1.27)
					(thickness 0.15)
				)
				(justify right)
			)
		)
		(property "Tolerance" "1%"
			(at 176.53 156.21 0)
			(effects
				(font
					(size 1.27 1.27)
				)
				(justify left bottom)
				(hide yes)
			)
		)
		(pin "2"
		)
		(pin "1"
		)
		(instances
			(project "OCuLink to 10GbE adapter"
				(path ""
					(reference "R142")
					(unit 1)
				)
			)
		)
	)
	(symbol
		(lib_id "antmicroResistors0402:R_100R_0402")
		(at 180.34 81.28 90)
		(unit 1)
		(exclude_from_sim no)
		(in_bom yes)
		(on_board yes)
		(dnp no)
		(property "Reference" "R141"
			(at 181.864 77.47 90)
			(effects
				(font
					(size 1.27 1.27)
					(thickness 0.15)
				)
				(justify right)
			)
		)
		(property "Value" "R_100R_0402"
			(at 193.04 60.96 0)
			(effects
				(font
					(size 1.27 1.27)
					(thickness 0.15)
				)
				(justify left bottom)
				(hide yes)
			)
		)
		(property "Footprint" "antmicro-footprints:R_0402_1005Metric"
			(at 195.58 60.96 0)
			(effects
				(font
					(size 1.27 1.27)
					(thickness 0.15)
				)
				(justify left bottom)
				(hide yes)
			)
		)
		(property "Datasheet" "https://www.bourns.com/docs/product-datasheets/cr.pdf"
			(at 198.12 60.96 0)
			(effects
				(font
					(size 1.27 1.27)
					(thickness 0.15)
				)
				(justify left bottom)
				(hide yes)
			)
		)
		(property "Description" "SMD Chip Resistor, 100 ohm, ± 1%, 62.5 mW, 0402 [1005 Metric], Thick Film, General Purpose"
			(at 180.34 81.28 0)
			(effects
				(font
					(size 1.27 1.27)
				)
				(hide yes)
			)
		)
		(property "MPN" "CR0402-FX-1000GLF"
			(at 200.66 60.96 0)
			(effects
				(font
					(size 1.27 1.27)
					(thickness 0.15)
				)
				(justify left bottom)
				(hide yes)
			)
		)
		(property "Manufacturer" "Bourns"
			(at 203.2 60.96 0)
			(effects
				(font
					(size 1.27 1.27)
					(thickness 0.15)
				)
				(justify left bottom)
				(hide yes)
			)
		)
		(property "License" "Apache-2.0"
			(at 205.74 60.96 0)
			(effects
				(font
					(size 1.27 1.27)
					(thickness 0.15)
				)
				(justify left bottom)
				(hide yes)
			)
		)
		(property "Author" "Antmicro"
			(at 208.28 60.96 0)
			(effects
				(font
					(size 1.27 1.27)
					(thickness 0.15)
				)
				(justify left bottom)
				(hide yes)
			)
		)
		(property "Val" "100R"
			(at 181.864 80.01 90)
			(effects
				(font
					(size 1.27 1.27)
					(thickness 0.15)
				)
				(justify right)
			)
		)
		(property "Tolerance" "1%"
			(at 190.5 60.96 0)
			(effects
				(font
					(size 1.27 1.27)
				)
				(justify left bottom)
				(hide yes)
			)
		)
		(pin "2"
		)
		(pin "1"
		)
		(instances
			(project ""
				(path ""
					(reference "R141")
					(unit 1)
				)
			)
		)
	)
	(symbol
		(lib_id "antmicroResistors0402:R_1k_0402")
		(at 269.24 46.99 90)
		(unit 1)
		(exclude_from_sim no)
		(in_bom yes)
		(on_board yes)
		(dnp no)
		(property "Reference" "R129"
			(at 270.764 43.18 90)
			(effects
				(font
					(size 1.27 1.27)
					(thickness 0.15)
				)
				(justify right)
			)
		)
		(property "Value" "R_1k_0402"
			(at 281.94 26.67 0)
			(effects
				(font
					(size 1.27 1.27)
					(thickness 0.15)
				)
				(justify left bottom)
				(hide yes)
			)
		)
		(property "Footprint" "antmicro-footprints:R_0402_1005Metric"
			(at 284.48 26.67 0)
			(effects
				(font
					(size 1.27 1.27)
					(thickness 0.15)
				)
				(justify left bottom)
				(hide yes)
			)
		)
		(property "Datasheet" "https://www.bourns.com/docs/product-datasheets/cr.pdf"
			(at 287.02 26.67 0)
			(effects
				(font
					(size 1.27 1.27)
					(thickness 0.15)
				)
				(justify left bottom)
				(hide yes)
			)
		)
		(property "Description" "SMD Chip Resistor, 1 kohm, ± 1%, 63 mW, 0402 [1005 Metric], Thick Film, General Purpose"
			(at 269.24 46.99 0)
			(effects
				(font
					(size 1.27 1.27)
				)
				(hide yes)
			)
		)
		(property "MPN" "CR0402-FX-1001GLF"
			(at 289.56 26.67 0)
			(effects
				(font
					(size 1.27 1.27)
					(thickness 0.15)
				)
				(justify left bottom)
				(hide yes)
			)
		)
		(property "Manufacturer" "Bourns"
			(at 292.1 26.67 0)
			(effects
				(font
					(size 1.27 1.27)
					(thickness 0.15)
				)
				(justify left bottom)
				(hide yes)
			)
		)
		(property "License" "Apache-2.0"
			(at 294.64 26.67 0)
			(effects
				(font
					(size 1.27 1.27)
					(thickness 0.15)
				)
				(justify left bottom)
				(hide yes)
			)
		)
		(property "Author" "Antmicro"
			(at 297.18 26.67 0)
			(effects
				(font
					(size 1.27 1.27)
					(thickness 0.15)
				)
				(justify left bottom)
				(hide yes)
			)
		)
		(property "Val" "1k"
			(at 270.764 45.72 90)
			(effects
				(font
					(size 1.27 1.27)
					(thickness 0.15)
				)
				(justify right)
			)
		)
		(property "Tolerance" "1%"
			(at 279.4 26.67 0)
			(effects
				(font
					(size 1.27 1.27)
				)
				(justify left bottom)
				(hide yes)
			)
		)
		(pin "2"
		)
		(pin "1"
		)
		(instances
			(project "OCuLink to 10GbE adapter"
				(path ""
					(reference "R129")
					(unit 1)
				)
			)
		)
	)
	(symbol
		(lib_id "antmicropower:GND")
		(at 276.86 64.77 0)
		(unit 1)
		(exclude_from_sim no)
		(in_bom yes)
		(on_board yes)
		(dnp no)
		(property "Reference" "#PWR0292"
			(at 285.75 67.31 0)
			(effects
				(font
					(size 1.27 1.27)
					(thickness 0.15)
				)
				(justify left bottom)
				(hide yes)
			)
		)
		(property "Value" "GND"
			(at 276.86 68.58 0)
			(effects
				(font
					(size 1.27 1.27)
					(thickness 0.15)
				)
			)
		)
		(property "Footprint" ""
			(at 285.75 72.39 0)
			(effects
				(font
					(size 1.27 1.27)
					(thickness 0.15)
				)
				(justify left bottom)
				(hide yes)
			)
		)
		(property "Datasheet" ""
			(at 285.75 77.47 0)
			(effects
				(font
					(size 1.27 1.27)
					(thickness 0.15)
				)
				(justify left bottom)
				(hide yes)
			)
		)
		(property "Description" ""
			(at 276.86 64.77 0)
			(effects
				(font
					(size 1.27 1.27)
				)
				(hide yes)
			)
		)
		(property "Author" "Antmicro"
			(at 285.75 72.39 0)
			(effects
				(font
					(size 1.27 1.27)
					(thickness 0.15)
				)
				(justify left bottom)
				(hide yes)
			)
		)
		(property "License" "Apache-2.0"
			(at 285.75 74.93 0)
			(effects
				(font
					(size 1.27 1.27)
					(thickness 0.15)
				)
				(justify left bottom)
				(hide yes)
			)
		)
		(pin "1"
		)
		(instances
			(project "OCuLink to 10GbE adapter"
				(path ""
					(reference "#PWR0292")
					(unit 1)
				)
			)
		)
	)
	(symbol
		(lib_id "antmicroResistors0402:R_100R_0402")
		(at 171.45 81.28 90)
		(unit 1)
		(exclude_from_sim no)
		(in_bom yes)
		(on_board yes)
		(dnp no)
		(property "Reference" "R140"
			(at 172.974 77.47 90)
			(effects
				(font
					(size 1.27 1.27)
					(thickness 0.15)
				)
				(justify right)
			)
		)
		(property "Value" "R_100R_0402"
			(at 184.15 60.96 0)
			(effects
				(font
					(size 1.27 1.27)
					(thickness 0.15)
				)
				(justify left bottom)
				(hide yes)
			)
		)
		(property "Footprint" "antmicro-footprints:R_0402_1005Metric"
			(at 186.69 60.96 0)
			(effects
				(font
					(size 1.27 1.27)
					(thickness 0.15)
				)
				(justify left bottom)
				(hide yes)
			)
		)
		(property "Datasheet" "https://www.bourns.com/docs/product-datasheets/cr.pdf"
			(at 189.23 60.96 0)
			(effects
				(font
					(size 1.27 1.27)
					(thickness 0.15)
				)
				(justify left bottom)
				(hide yes)
			)
		)
		(property "Description" "SMD Chip Resistor, 100 ohm, ± 1%, 62.5 mW, 0402 [1005 Metric], Thick Film, General Purpose"
			(at 171.45 81.28 0)
			(effects
				(font
					(size 1.27 1.27)
				)
				(hide yes)
			)
		)
		(property "MPN" "CR0402-FX-1000GLF"
			(at 191.77 60.96 0)
			(effects
				(font
					(size 1.27 1.27)
					(thickness 0.15)
				)
				(justify left bottom)
				(hide yes)
			)
		)
		(property "Manufacturer" "Bourns"
			(at 194.31 60.96 0)
			(effects
				(font
					(size 1.27 1.27)
					(thickness 0.15)
				)
				(justify left bottom)
				(hide yes)
			)
		)
		(property "License" "Apache-2.0"
			(at 196.85 60.96 0)
			(effects
				(font
					(size 1.27 1.27)
					(thickness 0.15)
				)
				(justify left bottom)
				(hide yes)
			)
		)
		(property "Author" "Antmicro"
			(at 199.39 60.96 0)
			(effects
				(font
					(size 1.27 1.27)
					(thickness 0.15)
				)
				(justify left bottom)
				(hide yes)
			)
		)
		(property "Val" "100R"
			(at 172.974 80.01 90)
			(effects
				(font
					(size 1.27 1.27)
					(thickness 0.15)
				)
				(justify right)
			)
		)
		(property "Tolerance" "1%"
			(at 181.61 60.96 0)
			(effects
				(font
					(size 1.27 1.27)
				)
				(justify left bottom)
				(hide yes)
			)
		)
		(pin "2"
		)
		(pin "1"
		)
		(instances
			(project "OCuLink to 10GbE adapter"
				(path ""
					(reference "R140")
					(unit 1)
				)
			)
		)
	)
	(symbol
		(lib_id "antmicropower:GND")
		(at 261.62 64.77 0)
		(unit 1)
		(exclude_from_sim no)
		(in_bom yes)
		(on_board yes)
		(dnp no)
		(property "Reference" "#PWR0290"
			(at 270.51 67.31 0)
			(effects
				(font
					(size 1.27 1.27)
					(thickness 0.15)
				)
				(justify left bottom)
				(hide yes)
			)
		)
		(property "Value" "GND"
			(at 261.62 68.58 0)
			(effects
				(font
					(size 1.27 1.27)
					(thickness 0.15)
				)
			)
		)
		(property "Footprint" ""
			(at 270.51 72.39 0)
			(effects
				(font
					(size 1.27 1.27)
					(thickness 0.15)
				)
				(justify left bottom)
				(hide yes)
			)
		)
		(property "Datasheet" ""
			(at 270.51 77.47 0)
			(effects
				(font
					(size 1.27 1.27)
					(thickness 0.15)
				)
				(justify left bottom)
				(hide yes)
			)
		)
		(property "Description" ""
			(at 261.62 64.77 0)
			(effects
				(font
					(size 1.27 1.27)
				)
				(hide yes)
			)
		)
		(property "Author" "Antmicro"
			(at 270.51 72.39 0)
			(effects
				(font
					(size 1.27 1.27)
					(thickness 0.15)
				)
				(justify left bottom)
				(hide yes)
			)
		)
		(property "License" "Apache-2.0"
			(at 270.51 74.93 0)
			(effects
				(font
					(size 1.27 1.27)
					(thickness 0.15)
				)
				(justify left bottom)
				(hide yes)
			)
		)
		(pin "1"
		)
		(instances
			(project "OCuLink to 10GbE adapter"
				(path ""
					(reference "#PWR0290")
					(unit 1)
				)
			)
		)
	)
	(symbol
		(lib_id "antmicroResistors0402:R_100R_0402")
		(at 118.11 81.28 90)
		(unit 1)
		(exclude_from_sim no)
		(in_bom yes)
		(on_board yes)
		(dnp no)
		(property "Reference" "R134"
			(at 119.634 77.47 90)
			(effects
				(font
					(size 1.27 1.27)
					(thickness 0.15)
				)
				(justify right)
			)
		)
		(property "Value" "R_100R_0402"
			(at 130.81 60.96 0)
			(effects
				(font
					(size 1.27 1.27)
					(thickness 0.15)
				)
				(justify left bottom)
				(hide yes)
			)
		)
		(property "Footprint" "antmicro-footprints:R_0402_1005Metric"
			(at 133.35 60.96 0)
			(effects
				(font
					(size 1.27 1.27)
					(thickness 0.15)
				)
				(justify left bottom)
				(hide yes)
			)
		)
		(property "Datasheet" "https://www.bourns.com/docs/product-datasheets/cr.pdf"
			(at 135.89 60.96 0)
			(effects
				(font
					(size 1.27 1.27)
					(thickness 0.15)
				)
				(justify left bottom)
				(hide yes)
			)
		)
		(property "Description" "SMD Chip Resistor, 100 ohm, ± 1%, 62.5 mW, 0402 [1005 Metric], Thick Film, General Purpose"
			(at 118.11 81.28 0)
			(effects
				(font
					(size 1.27 1.27)
				)
				(hide yes)
			)
		)
		(property "MPN" "CR0402-FX-1000GLF"
			(at 138.43 60.96 0)
			(effects
				(font
					(size 1.27 1.27)
					(thickness 0.15)
				)
				(justify left bottom)
				(hide yes)
			)
		)
		(property "Manufacturer" "Bourns"
			(at 140.97 60.96 0)
			(effects
				(font
					(size 1.27 1.27)
					(thickness 0.15)
				)
				(justify left bottom)
				(hide yes)
			)
		)
		(property "License" "Apache-2.0"
			(at 143.51 60.96 0)
			(effects
				(font
					(size 1.27 1.27)
					(thickness 0.15)
				)
				(justify left bottom)
				(hide yes)
			)
		)
		(property "Author" "Antmicro"
			(at 146.05 60.96 0)
			(effects
				(font
					(size 1.27 1.27)
					(thickness 0.15)
				)
				(justify left bottom)
				(hide yes)
			)
		)
		(property "Val" "100R"
			(at 119.634 80.01 90)
			(effects
				(font
					(size 1.27 1.27)
					(thickness 0.15)
				)
				(justify right)
			)
		)
		(property "Tolerance" "1%"
			(at 128.27 60.96 0)
			(effects
				(font
					(size 1.27 1.27)
				)
				(justify left bottom)
				(hide yes)
			)
		)
		(pin "2"
		)
		(pin "1"
		)
		(instances
			(project "OCuLink to 10GbE adapter"
				(path ""
					(reference "R134")
					(unit 1)
				)
			)
		)
	)
	(symbol
		(lib_id "antmicropower:GND")
		(at 118.11 83.82 0)
		(unit 1)
		(exclude_from_sim no)
		(in_bom yes)
		(on_board yes)
		(dnp no)
		(property "Reference" "#PWR0293"
			(at 127 86.36 0)
			(effects
				(font
					(size 1.27 1.27)
					(thickness 0.15)
				)
				(justify left bottom)
				(hide yes)
			)
		)
		(property "Value" "GND"
			(at 118.11 87.63 0)
			(effects
				(font
					(size 1.27 1.27)
					(thickness 0.15)
				)
			)
		)
		(property "Footprint" ""
			(at 127 91.44 0)
			(effects
				(font
					(size 1.27 1.27)
					(thickness 0.15)
				)
				(justify left bottom)
				(hide yes)
			)
		)
		(property "Datasheet" ""
			(at 127 96.52 0)
			(effects
				(font
					(size 1.27 1.27)
					(thickness 0.15)
				)
				(justify left bottom)
				(hide yes)
			)
		)
		(property "Description" ""
			(at 118.11 83.82 0)
			(effects
				(font
					(size 1.27 1.27)
				)
				(hide yes)
			)
		)
		(property "Author" "Antmicro"
			(at 127 91.44 0)
			(effects
				(font
					(size 1.27 1.27)
					(thickness 0.15)
				)
				(justify left bottom)
				(hide yes)
			)
		)
		(property "License" "Apache-2.0"
			(at 127 93.98 0)
			(effects
				(font
					(size 1.27 1.27)
					(thickness 0.15)
				)
				(justify left bottom)
				(hide yes)
			)
		)
		(pin "1"
		)
		(instances
			(project "OCuLink to 10GbE adapter"
				(path ""
					(reference "#PWR0293")
					(unit 1)
				)
			)
		)
	)
	(symbol
		(lib_id "antmicropower:GND")
		(at 269.24 64.77 0)
		(unit 1)
		(exclude_from_sim no)
		(in_bom yes)
		(on_board yes)
		(dnp no)
		(property "Reference" "#PWR0291"
			(at 278.13 67.31 0)
			(effects
				(font
					(size 1.27 1.27)
					(thickness 0.15)
				)
				(justify left bottom)
				(hide yes)
			)
		)
		(property "Value" "GND"
			(at 269.24 68.58 0)
			(effects
				(font
					(size 1.27 1.27)
					(thickness 0.15)
				)
			)
		)
		(property "Footprint" ""
			(at 278.13 72.39 0)
			(effects
				(font
					(size 1.27 1.27)
					(thickness 0.15)
				)
				(justify left bottom)
				(hide yes)
			)
		)
		(property "Datasheet" ""
			(at 278.13 77.47 0)
			(effects
				(font
					(size 1.27 1.27)
					(thickness 0.15)
				)
				(justify left bottom)
				(hide yes)
			)
		)
		(property "Description" ""
			(at 269.24 64.77 0)
			(effects
				(font
					(size 1.27 1.27)
				)
				(hide yes)
			)
		)
		(property "Author" "Antmicro"
			(at 278.13 72.39 0)
			(effects
				(font
					(size 1.27 1.27)
					(thickness 0.15)
				)
				(justify left bottom)
				(hide yes)
			)
		)
		(property "License" "Apache-2.0"
			(at 278.13 74.93 0)
			(effects
				(font
					(size 1.27 1.27)
					(thickness 0.15)
				)
				(justify left bottom)
				(hide yes)
			)
		)
		(pin "1"
		)
		(instances
			(project "OCuLink to 10GbE adapter"
				(path ""
					(reference "#PWR0291")
					(unit 1)
				)
			)
		)
	)
	(symbol
		(lib_id "antmicroResistors0402:R_10k_0402")
		(at 261.62 62.23 90)
		(unit 1)
		(exclude_from_sim no)
		(in_bom yes)
		(on_board yes)
		(dnp no)
		(property "Reference" "R131"
			(at 263.144 58.42 90)
			(effects
				(font
					(size 1.27 1.27)
					(thickness 0.15)
				)
				(justify right)
			)
		)
		(property "Value" "R_10k_0402"
			(at 274.32 41.91 0)
			(effects
				(font
					(size 1.27 1.27)
					(thickness 0.15)
				)
				(justify left bottom)
				(hide yes)
			)
		)
		(property "Footprint" "antmicro-footprints:R_0402_1005Metric"
			(at 276.86 41.91 0)
			(effects
				(font
					(size 1.27 1.27)
					(thickness 0.15)
				)
				(justify left bottom)
				(hide yes)
			)
		)
		(property "Datasheet" "https://www.bourns.com/docs/product-datasheets/cr.pdf"
			(at 279.4 41.91 0)
			(effects
				(font
					(size 1.27 1.27)
					(thickness 0.15)
				)
				(justify left bottom)
				(hide yes)
			)
		)
		(property "Description" "SMD Chip Resistor, 10 kohm, ± 1%, 62.5 mW, 0402 [1005 Metric], Thick Film, General Purpose"
			(at 261.62 62.23 0)
			(effects
				(font
					(size 1.27 1.27)
				)
				(hide yes)
			)
		)
		(property "MPN" "CR0402-FX-1002GLF"
			(at 281.94 41.91 0)
			(effects
				(font
					(size 1.27 1.27)
					(thickness 0.15)
				)
				(justify left bottom)
				(hide yes)
			)
		)
		(property "Manufacturer" "Bourns"
			(at 284.48 41.91 0)
			(effects
				(font
					(size 1.27 1.27)
					(thickness 0.15)
				)
				(justify left bottom)
				(hide yes)
			)
		)
		(property "License" "Apache-2.0"
			(at 287.02 41.91 0)
			(effects
				(font
					(size 1.27 1.27)
					(thickness 0.15)
				)
				(justify left bottom)
				(hide yes)
			)
		)
		(property "Author" "Antmicro"
			(at 289.56 41.91 0)
			(effects
				(font
					(size 1.27 1.27)
					(thickness 0.15)
				)
				(justify left bottom)
				(hide yes)
			)
		)
		(property "Val" "10k"
			(at 263.144 60.96 90)
			(effects
				(font
					(size 1.27 1.27)
					(thickness 0.15)
				)
				(justify right)
			)
		)
		(property "Tolerance" "1%"
			(at 271.78 41.91 0)
			(effects
				(font
					(size 1.27 1.27)
				)
				(justify left bottom)
				(hide yes)
			)
		)
		(pin "1"
		)
		(pin "2"
		)
		(instances
			(project ""
				(path ""
					(reference "R131")
					(unit 1)
				)
			)
		)
	)
	(symbol
		(lib_id "antmicropower:GND")
		(at 180.34 83.82 0)
		(unit 1)
		(exclude_from_sim no)
		(in_bom yes)
		(on_board yes)
		(dnp no)
		(property "Reference" "#PWR0300"
			(at 189.23 86.36 0)
			(effects
				(font
					(size 1.27 1.27)
					(thickness 0.15)
				)
				(justify left bottom)
				(hide yes)
			)
		)
		(property "Value" "GND"
			(at 180.34 87.63 0)
			(effects
				(font
					(size 1.27 1.27)
					(thickness 0.15)
				)
			)
		)
		(property "Footprint" ""
			(at 189.23 91.44 0)
			(effects
				(font
					(size 1.27 1.27)
					(thickness 0.15)
				)
				(justify left bottom)
				(hide yes)
			)
		)
		(property "Datasheet" ""
			(at 189.23 96.52 0)
			(effects
				(font
					(size 1.27 1.27)
					(thickness 0.15)
				)
				(justify left bottom)
				(hide yes)
			)
		)
		(property "Description" ""
			(at 180.34 83.82 0)
			(effects
				(font
					(size 1.27 1.27)
				)
				(hide yes)
			)
		)
		(property "Author" "Antmicro"
			(at 189.23 91.44 0)
			(effects
				(font
					(size 1.27 1.27)
					(thickness 0.15)
				)
				(justify left bottom)
				(hide yes)
			)
		)
		(property "License" "Apache-2.0"
			(at 189.23 93.98 0)
			(effects
				(font
					(size 1.27 1.27)
					(thickness 0.15)
				)
				(justify left bottom)
				(hide yes)
			)
		)
		(pin "1"
		)
		(instances
			(project "OCuLink to 10GbE adapter"
				(path ""
					(reference "#PWR0300")
					(unit 1)
				)
			)
		)
	)
	(symbol
		(lib_id "antmicroResistors0402:R_10k_0402")
		(at 276.86 62.23 90)
		(unit 1)
		(exclude_from_sim no)
		(in_bom yes)
		(on_board yes)
		(dnp no)
		(property "Reference" "R133"
			(at 278.384 58.42 90)
			(effects
				(font
					(size 1.27 1.27)
					(thickness 0.15)
				)
				(justify right)
			)
		)
		(property "Value" "R_10k_0402"
			(at 289.56 41.91 0)
			(effects
				(font
					(size 1.27 1.27)
					(thickness 0.15)
				)
				(justify left bottom)
				(hide yes)
			)
		)
		(property "Footprint" "antmicro-footprints:R_0402_1005Metric"
			(at 292.1 41.91 0)
			(effects
				(font
					(size 1.27 1.27)
					(thickness 0.15)
				)
				(justify left bottom)
				(hide yes)
			)
		)
		(property "Datasheet" "https://www.bourns.com/docs/product-datasheets/cr.pdf"
			(at 294.64 41.91 0)
			(effects
				(font
					(size 1.27 1.27)
					(thickness 0.15)
				)
				(justify left bottom)
				(hide yes)
			)
		)
		(property "Description" "SMD Chip Resistor, 10 kohm, ± 1%, 62.5 mW, 0402 [1005 Metric], Thick Film, General Purpose"
			(at 276.86 62.23 0)
			(effects
				(font
					(size 1.27 1.27)
				)
				(hide yes)
			)
		)
		(property "MPN" "CR0402-FX-1002GLF"
			(at 297.18 41.91 0)
			(effects
				(font
					(size 1.27 1.27)
					(thickness 0.15)
				)
				(justify left bottom)
				(hide yes)
			)
		)
		(property "Manufacturer" "Bourns"
			(at 299.72 41.91 0)
			(effects
				(font
					(size 1.27 1.27)
					(thickness 0.15)
				)
				(justify left bottom)
				(hide yes)
			)
		)
		(property "License" "Apache-2.0"
			(at 302.26 41.91 0)
			(effects
				(font
					(size 1.27 1.27)
					(thickness 0.15)
				)
				(justify left bottom)
				(hide yes)
			)
		)
		(property "Author" "Antmicro"
			(at 304.8 41.91 0)
			(effects
				(font
					(size 1.27 1.27)
					(thickness 0.15)
				)
				(justify left bottom)
				(hide yes)
			)
		)
		(property "Val" "10k"
			(at 278.384 60.96 90)
			(effects
				(font
					(size 1.27 1.27)
					(thickness 0.15)
				)
				(justify right)
			)
		)
		(property "Tolerance" "1%"
			(at 287.02 41.91 0)
			(effects
				(font
					(size 1.27 1.27)
				)
				(justify left bottom)
				(hide yes)
			)
		)
		(pin "1"
		)
		(pin "2"
		)
		(instances
			(project "OCuLink to 10GbE adapter"
				(path ""
					(reference "R133")
					(unit 1)
				)
			)
		)
	)
	(symbol
		(lib_id "antmicropower:GND")
		(at 153.67 83.82 0)
		(unit 1)
		(exclude_from_sim no)
		(in_bom yes)
		(on_board yes)
		(dnp no)
		(property "Reference" "#PWR0297"
			(at 162.56 86.36 0)
			(effects
				(font
					(size 1.27 1.27)
					(thickness 0.15)
				)
				(justify left bottom)
				(hide yes)
			)
		)
		(property "Value" "GND"
			(at 153.67 87.63 0)
			(effects
				(font
					(size 1.27 1.27)
					(thickness 0.15)
				)
			)
		)
		(property "Footprint" ""
			(at 162.56 91.44 0)
			(effects
				(font
					(size 1.27 1.27)
					(thickness 0.15)
				)
				(justify left bottom)
				(hide yes)
			)
		)
		(property "Datasheet" ""
			(at 162.56 96.52 0)
			(effects
				(font
					(size 1.27 1.27)
					(thickness 0.15)
				)
				(justify left bottom)
				(hide yes)
			)
		)
		(property "Description" ""
			(at 153.67 83.82 0)
			(effects
				(font
					(size 1.27 1.27)
				)
				(hide yes)
			)
		)
		(property "Author" "Antmicro"
			(at 162.56 91.44 0)
			(effects
				(font
					(size 1.27 1.27)
					(thickness 0.15)
				)
				(justify left bottom)
				(hide yes)
			)
		)
		(property "License" "Apache-2.0"
			(at 162.56 93.98 0)
			(effects
				(font
					(size 1.27 1.27)
					(thickness 0.15)
				)
				(justify left bottom)
				(hide yes)
			)
		)
		(pin "1"
		)
		(instances
			(project "OCuLink to 10GbE adapter"
				(path ""
					(reference "#PWR0297")
					(unit 1)
				)
			)
		)
	)
	(symbol
		(lib_id "antmicroResistors0402:R_100R_0402")
		(at 127 81.28 90)
		(unit 1)
		(exclude_from_sim no)
		(in_bom yes)
		(on_board yes)
		(dnp no)
		(property "Reference" "R135"
			(at 128.524 77.47 90)
			(effects
				(font
					(size 1.27 1.27)
					(thickness 0.15)
				)
				(justify right)
			)
		)
		(property "Value" "R_100R_0402"
			(at 139.7 60.96 0)
			(effects
				(font
					(size 1.27 1.27)
					(thickness 0.15)
				)
				(justify left bottom)
				(hide yes)
			)
		)
		(property "Footprint" "antmicro-footprints:R_0402_1005Metric"
			(at 142.24 60.96 0)
			(effects
				(font
					(size 1.27 1.27)
					(thickness 0.15)
				)
				(justify left bottom)
				(hide yes)
			)
		)
		(property "Datasheet" "https://www.bourns.com/docs/product-datasheets/cr.pdf"
			(at 144.78 60.96 0)
			(effects
				(font
					(size 1.27 1.27)
					(thickness 0.15)
				)
				(justify left bottom)
				(hide yes)
			)
		)
		(property "Description" "SMD Chip Resistor, 100 ohm, ± 1%, 62.5 mW, 0402 [1005 Metric], Thick Film, General Purpose"
			(at 127 81.28 0)
			(effects
				(font
					(size 1.27 1.27)
				)
				(hide yes)
			)
		)
		(property "MPN" "CR0402-FX-1000GLF"
			(at 147.32 60.96 0)
			(effects
				(font
					(size 1.27 1.27)
					(thickness 0.15)
				)
				(justify left bottom)
				(hide yes)
			)
		)
		(property "Manufacturer" "Bourns"
			(at 149.86 60.96 0)
			(effects
				(font
					(size 1.27 1.27)
					(thickness 0.15)
				)
				(justify left bottom)
				(hide yes)
			)
		)
		(property "License" "Apache-2.0"
			(at 152.4 60.96 0)
			(effects
				(font
					(size 1.27 1.27)
					(thickness 0.15)
				)
				(justify left bottom)
				(hide yes)
			)
		)
		(property "Author" "Antmicro"
			(at 154.94 60.96 0)
			(effects
				(font
					(size 1.27 1.27)
					(thickness 0.15)
				)
				(justify left bottom)
				(hide yes)
			)
		)
		(property "Val" "100R"
			(at 128.524 80.01 90)
			(effects
				(font
					(size 1.27 1.27)
					(thickness 0.15)
				)
				(justify right)
			)
		)
		(property "Tolerance" "1%"
			(at 137.16 60.96 0)
			(effects
				(font
					(size 1.27 1.27)
				)
				(justify left bottom)
				(hide yes)
			)
		)
		(pin "2"
		)
		(pin "1"
		)
		(instances
			(project "OCuLink to 10GbE adapter"
				(path ""
					(reference "R135")
					(unit 1)
				)
			)
		)
	)
	(symbol
		(lib_id "antmicroResistors0402:R_1k_0402")
		(at 261.62 46.99 90)
		(unit 1)
		(exclude_from_sim no)
		(in_bom yes)
		(on_board yes)
		(dnp no)
		(property "Reference" "R128"
			(at 263.144 43.18 90)
			(effects
				(font
					(size 1.27 1.27)
					(thickness 0.15)
				)
				(justify right)
			)
		)
		(property "Value" "R_1k_0402"
			(at 274.32 26.67 0)
			(effects
				(font
					(size 1.27 1.27)
					(thickness 0.15)
				)
				(justify left bottom)
				(hide yes)
			)
		)
		(property "Footprint" "antmicro-footprints:R_0402_1005Metric"
			(at 276.86 26.67 0)
			(effects
				(font
					(size 1.27 1.27)
					(thickness 0.15)
				)
				(justify left bottom)
				(hide yes)
			)
		)
		(property "Datasheet" "https://www.bourns.com/docs/product-datasheets/cr.pdf"
			(at 279.4 26.67 0)
			(effects
				(font
					(size 1.27 1.27)
					(thickness 0.15)
				)
				(justify left bottom)
				(hide yes)
			)
		)
		(property "Description" "SMD Chip Resistor, 1 kohm, ± 1%, 63 mW, 0402 [1005 Metric], Thick Film, General Purpose"
			(at 261.62 46.99 0)
			(effects
				(font
					(size 1.27 1.27)
				)
				(hide yes)
			)
		)
		(property "MPN" "CR0402-FX-1001GLF"
			(at 281.94 26.67 0)
			(effects
				(font
					(size 1.27 1.27)
					(thickness 0.15)
				)
				(justify left bottom)
				(hide yes)
			)
		)
		(property "Manufacturer" "Bourns"
			(at 284.48 26.67 0)
			(effects
				(font
					(size 1.27 1.27)
					(thickness 0.15)
				)
				(justify left bottom)
				(hide yes)
			)
		)
		(property "License" "Apache-2.0"
			(at 287.02 26.67 0)
			(effects
				(font
					(size 1.27 1.27)
					(thickness 0.15)
				)
				(justify left bottom)
				(hide yes)
			)
		)
		(property "Author" "Antmicro"
			(at 289.56 26.67 0)
			(effects
				(font
					(size 1.27 1.27)
					(thickness 0.15)
				)
				(justify left bottom)
				(hide yes)
			)
		)
		(property "Val" "1k"
			(at 263.144 45.72 90)
			(effects
				(font
					(size 1.27 1.27)
					(thickness 0.15)
				)
				(justify right)
			)
		)
		(property "Tolerance" "1%"
			(at 271.78 26.67 0)
			(effects
				(font
					(size 1.27 1.27)
				)
				(justify left bottom)
				(hide yes)
			)
		)
		(pin "2"
		)
		(pin "1"
		)
		(instances
			(project ""
				(path ""
					(reference "R128")
					(unit 1)
				)
			)
		)
	)
	(symbol
		(lib_id "antmicroResistors0402:R_100R_0402")
		(at 144.78 81.28 90)
		(unit 1)
		(exclude_from_sim no)
		(in_bom yes)
		(on_board yes)
		(dnp no)
		(property "Reference" "R137"
			(at 146.304 77.47 90)
			(effects
				(font
					(size 1.27 1.27)
					(thickness 0.15)
				)
				(justify right)
			)
		)
		(property "Value" "R_100R_0402"
			(at 157.48 60.96 0)
			(effects
				(font
					(size 1.27 1.27)
					(thickness 0.15)
				)
				(justify left bottom)
				(hide yes)
			)
		)
		(property "Footprint" "antmicro-footprints:R_0402_1005Metric"
			(at 160.02 60.96 0)
			(effects
				(font
					(size 1.27 1.27)
					(thickness 0.15)
				)
				(justify left bottom)
				(hide yes)
			)
		)
		(property "Datasheet" "https://www.bourns.com/docs/product-datasheets/cr.pdf"
			(at 162.56 60.96 0)
			(effects
				(font
					(size 1.27 1.27)
					(thickness 0.15)
				)
				(justify left bottom)
				(hide yes)
			)
		)
		(property "Description" "SMD Chip Resistor, 100 ohm, ± 1%, 62.5 mW, 0402 [1005 Metric], Thick Film, General Purpose"
			(at 144.78 81.28 0)
			(effects
				(font
					(size 1.27 1.27)
				)
				(hide yes)
			)
		)
		(property "MPN" "CR0402-FX-1000GLF"
			(at 165.1 60.96 0)
			(effects
				(font
					(size 1.27 1.27)
					(thickness 0.15)
				)
				(justify left bottom)
				(hide yes)
			)
		)
		(property "Manufacturer" "Bourns"
			(at 167.64 60.96 0)
			(effects
				(font
					(size 1.27 1.27)
					(thickness 0.15)
				)
				(justify left bottom)
				(hide yes)
			)
		)
		(property "License" "Apache-2.0"
			(at 170.18 60.96 0)
			(effects
				(font
					(size 1.27 1.27)
					(thickness 0.15)
				)
				(justify left bottom)
				(hide yes)
			)
		)
		(property "Author" "Antmicro"
			(at 172.72 60.96 0)
			(effects
				(font
					(size 1.27 1.27)
					(thickness 0.15)
				)
				(justify left bottom)
				(hide yes)
			)
		)
		(property "Val" "100R"
			(at 146.304 80.01 90)
			(effects
				(font
					(size 1.27 1.27)
					(thickness 0.15)
				)
				(justify right)
			)
		)
		(property "Tolerance" "1%"
			(at 154.94 60.96 0)
			(effects
				(font
					(size 1.27 1.27)
				)
				(justify left bottom)
				(hide yes)
			)
		)
		(pin "2"
		)
		(pin "1"
		)
		(instances
			(project "OCuLink to 10GbE adapter"
				(path ""
					(reference "R137")
					(unit 1)
				)
			)
		)
	)
	(symbol
		(lib_id "antmicropower:GND")
		(at 135.89 83.82 0)
		(unit 1)
		(exclude_from_sim no)
		(in_bom yes)
		(on_board yes)
		(dnp no)
		(property "Reference" "#PWR0295"
			(at 144.78 86.36 0)
			(effects
				(font
					(size 1.27 1.27)
					(thickness 0.15)
				)
				(justify left bottom)
				(hide yes)
			)
		)
		(property "Value" "GND"
			(at 135.89 87.63 0)
			(effects
				(font
					(size 1.27 1.27)
					(thickness 0.15)
				)
			)
		)
		(property "Footprint" ""
			(at 144.78 91.44 0)
			(effects
				(font
					(size 1.27 1.27)
					(thickness 0.15)
				)
				(justify left bottom)
				(hide yes)
			)
		)
		(property "Datasheet" ""
			(at 144.78 96.52 0)
			(effects
				(font
					(size 1.27 1.27)
					(thickness 0.15)
				)
				(justify left bottom)
				(hide yes)
			)
		)
		(property "Description" ""
			(at 135.89 83.82 0)
			(effects
				(font
					(size 1.27 1.27)
				)
				(hide yes)
			)
		)
		(property "Author" "Antmicro"
			(at 144.78 91.44 0)
			(effects
				(font
					(size 1.27 1.27)
					(thickness 0.15)
				)
				(justify left bottom)
				(hide yes)
			)
		)
		(property "License" "Apache-2.0"
			(at 144.78 93.98 0)
			(effects
				(font
					(size 1.27 1.27)
					(thickness 0.15)
				)
				(justify left bottom)
				(hide yes)
			)
		)
		(pin "1"
		)
		(instances
			(project "OCuLink to 10GbE adapter"
				(path ""
					(reference "#PWR0295")
					(unit 1)
				)
			)
		)
	)
	(symbol
		(lib_id "antmicroInterfaceControllers:EZX710AT2_S_LMR5")
		(at 195.58 179.07 0)
		(unit 7)
		(exclude_from_sim no)
		(in_bom yes)
		(on_board yes)
		(dnp no)
		(fields_autoplaced yes)
		(property "Reference" "U9"
			(at 218.44 171.45 0)
			(effects
				(font
					(size 1.27 1.27)
					(thickness 0.15)
				)
			)
		)
		(property "Value" "EZX710AT2_S_LMR5"
			(at 271.78 184.15 0)
			(effects
				(font
					(size 1.27 1.27)
					(thickness 0.15)
				)
				(justify left bottom)
				(hide yes)
			)
		)
		(property "Footprint" "antmicro-footprints:FCBGA-503_22x22mm_Layout21x24_P1mm"
			(at 271.78 186.69 0)
			(effects
				(font
					(size 1.27 1.27)
					(thickness 0.15)
				)
				(justify left bottom)
				(hide yes)
			)
		)
		(property "Datasheet" "https://www.google.com/url?sa=t&source=web&rct=j&opi=89978449&url=https://cdrdv2-public.intel.com/596333/596333_X710-TM4_Datasheet_v_2_4.pdf&ved=2ahUKEwiSuv20_sCOAxXVCRAIHdxGO_UQFnoECBEQAQ&usg=AOvVaw1CjGyrGWE8ZvOdw4VBsY6U"
			(at 271.78 189.23 0)
			(effects
				(font
					(size 1.27 1.27)
					(thickness 0.15)
				)
				(justify left bottom)
				(hide yes)
			)
		)
		(property "Description" "Ethernet ICs Intel Ethernet Controller 10 Gigabit X7"
			(at 271.78 191.77 0)
			(effects
				(font
					(size 1.27 1.27)
					(thickness 0.15)
				)
				(justify left bottom)
				(hide yes)
			)
		)
		(property "MPN" "EZX710AT2 S LMR5"
			(at 218.44 173.99 0)
			(effects
				(font
					(size 1.27 1.27)
					(thickness 0.15)
				)
			)
		)
		(property "Manufacturer" "Intel"
			(at 271.78 194.31 0)
			(effects
				(font
					(size 1.27 1.27)
					(thickness 0.15)
				)
				(justify left bottom)
				(hide yes)
			)
		)
		(property "Author" "Antmicro"
			(at 271.78 196.85 0)
			(effects
				(font
					(size 1.27 1.27)
					(thickness 0.15)
				)
				(justify left bottom)
				(hide yes)
			)
		)
		(property "License" "Apache-2.0"
			(at 271.78 199.39 0)
			(effects
				(font
					(size 1.27 1.27)
					(thickness 0.15)
				)
				(justify left bottom)
				(hide yes)
			)
		)
		(pin "B26"
		)
		(pin "E7"
		)
		(pin "G9"
		)
		(pin "E5"
		)
		(pin "A17"
		)
		(pin "J15"
		)
		(pin "P34"
		)
		(pin "AD30"
		)
		(pin "J7"
		)
		(pin "C1"
		)
		(pin "G37"
		)
		(pin "N37"
		)
		(pin "F38"
		)
		(pin "B2"
		)
		(pin "N29"
		)
		(pin "D4"
		)
		(pin "Y24"
		)
		(pin "N35"
		)
		(pin "C5"
		)
		(pin "V42"
		)
		(pin "M20"
		)
		(pin "P10"
		)
		(pin "L37"
		)
		(pin "B34"
		)
		(pin "U37"
		)
		(pin "AC7"
		)
		(pin "M4"
		)
		(pin "U35"
		)
		(pin "D18"
		)
		(pin "H16"
		)
		(pin "V30"
		)
		(pin "B38"
		)
		(pin "W29"
		)
		(pin "AB22"
		)
		(pin "AC15"
		)
		(pin "B28"
		)
		(pin "G3"
		)
		(pin "P32"
		)
		(pin "H14"
		)
		(pin "G13"
		)
		(pin "B30"
		)
		(pin "D22"
		)
		(pin "V10"
		)
		(pin "B24"
		)
		(pin "AD4"
		)
		(pin "AC5"
		)
		(pin "AA5"
		)
		(pin "V24"
		)
		(pin "V6"
		)
		(pin "D10"
		)
		(pin "AD20"
		)
		(pin "T26"
		)
		(pin "T10"
		)
		(pin "T12"
		)
		(pin "AD6"
		)
		(pin "H8"
		)
		(pin "H28"
		)
		(pin "N15"
		)
		(pin "AC29"
		)
		(pin "N17"
		)
		(pin "W31"
		)
		(pin "Y12"
		)
		(pin "W23"
		)
		(pin "AD32"
		)
		(pin "AB16"
		)
		(pin "T28"
		)
		(pin "D24"
		)
		(pin "D26"
		)
		(pin "G17"
		)
		(pin "K32"
		)
		(pin "F24"
		)
		(pin "F26"
		)
		(pin "J31"
		)
		(pin "T30"
		)
		(pin "AD34"
		)
		(pin "AA27"
		)
		(pin "R17"
		)
		(pin "W13"
		)
		(pin "M26"
		)
		(pin "C9"
		)
		(pin "AA41"
		)
		(pin "AC27"
		)
		(pin "K2"
		)
		(pin "AB20"
		)
		(pin "R7"
		)
		(pin "N39"
		)
		(pin "D6"
		)
		(pin "M22"
		)
		(pin "M2"
		)
		(pin "AC9"
		)
		(pin "A3"
		)
		(pin "P2"
		)
		(pin "AA33"
		)
		(pin "A23"
		)
		(pin "E35"
		)
		(pin "U3"
		)
		(pin "V36"
		)
		(pin "K42"
		)
		(pin "R41"
		)
		(pin "R1"
		)
		(pin "AD22"
		)
		(pin "W7"
		)
		(pin "AB18"
		)
		(pin "E19"
		)
		(pin "AB12"
		)
		(pin "AD28"
		)
		(pin "AD40"
		)
		(pin "J1"
		)
		(pin "Y6"
		)
		(pin "Y8"
		)
		(pin "H36"
		)
		(pin "C13"
		)
		(pin "C23"
		)
		(pin "Y38"
		)
		(pin "U21"
		)
		(pin "F32"
		)
		(pin "F34"
		)
		(pin "A25"
		)
		(pin "N23"
		)
		(pin "W41"
		)
		(pin "AC31"
		)
		(pin "D12"
		)
		(pin "K34"
		)
		(pin "AA23"
		)
		(pin "AC17"
		)
		(pin "V22"
		)
		(pin "AA39"
		)
		(pin "J41"
		)
		(pin "V14"
		)
		(pin "U23"
		)
		(pin "V16"
		)
		(pin "W35"
		)
		(pin "AC21"
		)
		(pin "D32"
		)
		(pin "L1"
		)
		(pin "P24"
		)
		(pin "J3"
		)
		(pin "AC41"
		)
		(pin "AD14"
		)
		(pin "K22"
		)
		(pin "A11"
		)
		(pin "AA15"
		)
		(pin "F2"
		)
		(pin "A9"
		)
		(pin "N27"
		)
		(pin "C19"
		)
		(pin "K30"
		)
		(pin "L23"
		)
		(pin "N41"
		)
		(pin "F20"
		)
		(pin "AB28"
		)
		(pin "AD12"
		)
		(pin "C21"
		)
		(pin "U9"
		)
		(pin "V20"
		)
		(pin "D20"
		)
		(pin "L21"
		)
		(pin "R15"
		)
		(pin "K4"
		)
		(pin "N1"
		)
		(pin "H12"
		)
		(pin "J23"
		)
		(pin "J5"
		)
		(pin "E9"
		)
		(pin "M28"
		)
		(pin "U1"
		)
		(pin "Y2"
		)
		(pin "G5"
		)
		(pin "K20"
		)
		(pin "M18"
		)
		(pin "V2"
		)
		(pin "AC39"
		)
		(pin "T32"
		)
		(pin "E25"
		)
		(pin "AD38"
		)
		(pin "H26"
		)
		(pin "AA31"
		)
		(pin "G31"
		)
		(pin "U27"
		)
		(pin "U17"
		)
		(pin "C11"
		)
		(pin "N3"
		)
		(pin "A37"
		)
		(pin "F6"
		)
		(pin "Y30"
		)
		(pin "U7"
		)
		(pin "G15"
		)
		(pin "C29"
		)
		(pin "E39"
		)
		(pin "A35"
		)
		(pin "L3"
		)
		(pin "N25"
		)
		(pin "R25"
		)
		(pin "J37"
		)
		(pin "H42"
		)
		(pin "AD24"
		)
		(pin "B14"
		)
		(pin "P6"
		)
		(pin "R31"
		)
		(pin "A5"
		)
		(pin "D14"
		)
		(pin "AB10"
		)
		(pin "B18"
		)
		(pin "A27"
		)
		(pin "T40"
		)
		(pin "AB40"
		)
		(pin "P4"
		)
		(pin "AA35"
		)
		(pin "F36"
		)
		(pin "K18"
		)
		(pin "K38"
		)
		(pin "N33"
		)
		(pin "Y26"
		)
		(pin "Y28"
		)
		(pin "G21"
		)
		(pin "AA1"
		)
		(pin "AB2"
		)
		(pin "V38"
		)
		(pin "J9"
		)
		(pin "B6"
		)
		(pin "L35"
		)
		(pin "N7"
		)
		(pin "AC1"
		)
		(pin "E23"
		)
		(pin "F40"
		)
		(pin "F42"
		)
		(pin "P36"
		)
		(pin "F4"
		)
		(pin "AD16"
		)
		(pin "R11"
		)
		(pin "R27"
		)
		(pin "J13"
		)
		(pin "M10"
		)
		(pin "Y4"
		)
		(pin "Y40"
		)
		(pin "L27"
		)
		(pin "L9"
		)
		(pin "K10"
		)
		(pin "L39"
		)
		(pin "U5"
		)
		(pin "AB42"
		)
		(pin "R5"
		)
		(pin "G23"
		)
		(pin "M8"
		)
		(pin "AD8"
		)
		(pin "M16"
		)
		(pin "M12"
		)
		(pin "E3"
		)
		(pin "B12"
		)
		(pin "R23"
		)
		(pin "W25"
		)
		(pin "H4"
		)
		(pin "F8"
		)
		(pin "AC23"
		)
		(pin "AA3"
		)
		(pin "B10"
		)
		(pin "E31"
		)
		(pin "E33"
		)
		(pin "G1"
		)
		(pin "F18"
		)
		(pin "W17"
		)
		(pin "K36"
		)
		(pin "AB26"
		)
		(pin "R13"
		)
		(pin "AB32"
		)
		(pin "V18"
		)
		(pin "D16"
		)
		(pin "AA37"
		)
		(pin "C31"
		)
		(pin "C41"
		)
		(pin "A41"
		)
		(pin "E1"
		)
		(pin "P38"
		)
		(pin "U19"
		)
		(pin "R29"
		)
		(pin "E37"
		)
		(pin "E29"
		)
		(pin "A21"
		)
		(pin "A31"
		)
		(pin "U29"
		)
		(pin "AB34"
		)
		(pin "E17"
		)
		(pin "W15"
		)
		(pin "H40"
		)
		(pin "M24"
		)
		(pin "U15"
		)
		(pin "H2"
		)
		(pin "N21"
		)
		(pin "W33"
		)
		(pin "J29"
		)
		(pin "T42"
		)
		(pin "A13"
		)
		(pin "AD26"
		)
		(pin "P28"
		)
		(pin "T24"
		)
		(pin "F12"
		)
		(pin "AD2"
		)
		(pin "H34"
		)
		(pin "J33"
		)
		(pin "P40"
		)
		(pin "C17"
		)
		(pin "W19"
		)
		(pin "M6"
		)
		(pin "H6"
		)
		(pin "M40"
		)
		(pin "D30"
		)
		(pin "F10"
		)
		(pin "Y14"
		)
		(pin "L29"
		)
		(pin "P22"
		)
		(pin "W1"
		)
		(pin "V28"
		)
		(pin "E11"
		)
		(pin "J25"
		)
		(pin "G27"
		)
		(pin "M34"
		)
		(pin "Y18"
		)
		(pin "K8"
		)
		(pin "AC35"
		)
		(pin "AD36"
		)
		(pin "G19"
		)
		(pin "G41"
		)
		(pin "W3"
		)
		(pin "C37"
		)
		(pin "C27"
		)
		(pin "Y22"
		)
		(pin "C35"
		)
		(pin "L41"
		)
		(pin "P30"
		)
		(pin "V8"
		)
		(pin "AB30"
		)
		(pin "A29"
		)
		(pin "B22"
		)
		(pin "B32"
		)
		(pin "T36"
		)
		(pin "AA17"
		)
		(pin "K12"
		)
		(pin "P8"
		)
		(pin "T22"
		)
		(pin "C15"
		)
		(pin "W9"
		)
		(pin "W11"
		)
		(pin "P42"
		)
		(pin "T6"
		)
		(pin "B40"
		)
		(pin "N9"
		)
		(pin "K6"
		)
		(pin "A33"
		)
		(pin "T38"
		)
		(pin "J35"
		)
		(pin "E41"
		)
		(pin "T2"
		)
		(pin "C3"
		)
		(pin "R3"
		)
		(pin "D8"
		)
		(pin "F28"
		)
		(pin "F30"
		)
		(pin "Y32"
		)
		(pin "Y36"
		)
		(pin "AC25"
		)
		(pin "T4"
		)
		(pin "V26"
		)
		(pin "B16"
		)
		(pin "V32"
		)
		(pin "H10"
		)
		(pin "A7"
		)
		(pin "R9"
		)
		(pin "N11"
		)
		(pin "R37"
		)
		(pin "W37"
		)
		(pin "V4"
		)
		(pin "T14"
		)
		(pin "T16"
		)
		(pin "J21"
		)
		(pin "AB14"
		)
		(pin "J17"
		)
		(pin "W5"
		)
		(pin "D34"
		)
		(pin "Y34"
		)
		(pin "M36"
		)
		(pin "AA25"
		)
		(pin "B4"
		)
		(pin "AA29"
		)
		(pin "K16"
		)
		(pin "V40"
		)
		(pin "AC37"
		)
		(pin "AB24"
		)
		(pin "AD18"
		)
		(pin "AA7"
		)
		(pin "V12"
		)
		(pin "AC13"
		)
		(pin "T8"
		)
		(pin "E21"
		)
		(pin "A19"
		)
		(pin "E27"
		)
		(pin "K14"
		)
		(pin "AA13"
		)
		(pin "P16"
		)
		(pin "P18"
		)
		(pin "H30"
		)
		(pin "N31"
		)
		(pin "P12"
		)
		(pin "P14"
		)
		(pin "B42"
		)
		(pin "G25"
		)
		(pin "U25"
		)
		(pin "A39"
		)
		(pin "J11"
		)
		(pin "G11"
		)
		(pin "G29"
		)
		(pin "R19"
		)
		(pin "AC11"
		)
		(pin "F22"
		)
		(pin "W39"
		)
		(pin "AA9"
		)
		(pin "AB38"
		)
		(pin "L31"
		)
		(pin "T34"
		)
		(pin "J39"
		)
		(pin "F14"
		)
		(pin "H24"
		)
		(pin "G35"
		)
		(pin "W21"
		)
		(pin "K40"
		)
		(pin "N19"
		)
		(pin "B20"
		)
		(pin "U31"
		)
		(pin "R21"
		)
		(pin "R39"
		)
		(pin "P20"
		)
		(pin "R35"
		)
		(pin "AD42"
		)
		(pin "K24"
		)
		(pin "AB4"
		)
		(pin "AC33"
		)
		(pin "B8"
		)
		(pin "U33"
		)
		(pin "H32"
		)
		(pin "L33"
		)
		(pin "J19"
		)
		(pin "U13"
		)
		(pin "C39"
		)
		(pin "H22"
		)
		(pin "AD10"
		)
		(pin "Y20"
		)
		(pin "E15"
		)
		(pin "AA21"
		)
		(pin "K26"
		)
		(pin "C25"
		)
		(pin "M42"
		)
		(pin "U41"
		)
		(pin "Y16"
		)
		(pin "D28"
		)
		(pin "D36"
		)
		(pin "Y10"
		)
		(pin "AC19"
		)
		(pin "AB8"
		)
		(pin "AB36"
		)
		(pin "P26"
		)
		(pin "D38"
		)
		(pin "D40"
		)
		(pin "AA19"
		)
		(pin "E13"
		)
		(pin "A15"
		)
		(pin "H20"
		)
		(pin "K28"
		)
		(pin "F16"
		)
		(pin "W27"
		)
		(pin "D42"
		)
		(pin "AB6"
		)
		(pin "M14"
		)
		(pin "M32"
		)
		(pin "N5"
		)
		(pin "U11"
		)
		(pin "J27"
		)
		(pin "M30"
		)
		(pin "C33"
		)
		(pin "C7"
		)
		(pin "L15"
		)
		(pin "G33"
		)
		(pin "L19"
		)
		(pin "L17"
		)
		(pin "L5"
		)
		(pin "L25"
		)
		(pin "M38"
		)
		(pin "T18"
		)
		(pin "T20"
		)
		(pin "H18"
		)
		(pin "G7"
		)
		(pin "B36"
		)
		(pin "U39"
		)
		(pin "G39"
		)
		(pin "D2"
		)
		(pin "R33"
		)
		(pin "L11"
		)
		(pin "AC3"
		)
		(pin "AA11"
		)
		(pin "H38"
		)
		(pin "N13"
		)
		(pin "L13"
		)
		(pin "L7"
		)
		(pin "Y42"
		)
		(pin "V34"
		)
		(instances
			(project "OCuLink to 10GbE adapter"
				(path ""
					(reference "U9")
					(unit 7)
				)
			)
		)
	)
	(symbol
		(lib_id "antmicropower:GND")
		(at 241.3 250.19 0)
		(unit 1)
		(exclude_from_sim no)
		(in_bom yes)
		(on_board yes)
		(dnp no)
		(property "Reference" "#PWR0317"
			(at 250.19 252.73 0)
			(effects
				(font
					(size 1.27 1.27)
					(thickness 0.15)
				)
				(justify left bottom)
				(hide yes)
			)
		)
		(property "Value" "GND"
			(at 241.3 254 0)
			(effects
				(font
					(size 1.27 1.27)
					(thickness 0.15)
				)
			)
		)
		(property "Footprint" ""
			(at 250.19 257.81 0)
			(effects
				(font
					(size 1.27 1.27)
					(thickness 0.15)
				)
				(justify left bottom)
				(hide yes)
			)
		)
		(property "Datasheet" ""
			(at 250.19 262.89 0)
			(effects
				(font
					(size 1.27 1.27)
					(thickness 0.15)
				)
				(justify left bottom)
				(hide yes)
			)
		)
		(property "Description" ""
			(at 241.3 250.19 0)
			(effects
				(font
					(size 1.27 1.27)
				)
				(hide yes)
			)
		)
		(property "Author" "Antmicro"
			(at 250.19 257.81 0)
			(effects
				(font
					(size 1.27 1.27)
					(thickness 0.15)
				)
				(justify left bottom)
				(hide yes)
			)
		)
		(property "License" "Apache-2.0"
			(at 250.19 260.35 0)
			(effects
				(font
					(size 1.27 1.27)
					(thickness 0.15)
				)
				(justify left bottom)
				(hide yes)
			)
		)
		(pin "1"
		)
		(instances
			(project "OCuLink to 10GbE adapter"
				(path ""
					(reference "#PWR0317")
					(unit 1)
				)
			)
		)
	)
	(symbol
		(lib_id "antmicroResistors0402:R_1k_0402")
		(at 173.99 176.53 90)
		(unit 1)
		(exclude_from_sim no)
		(in_bom yes)
		(on_board yes)
		(dnp no)
		(property "Reference" "R143"
			(at 175.514 172.72 90)
			(effects
				(font
					(size 1.27 1.27)
					(thickness 0.15)
				)
				(justify right)
			)
		)
		(property "Value" "R_1k_0402"
			(at 186.69 156.21 0)
			(effects
				(font
					(size 1.27 1.27)
					(thickness 0.15)
				)
				(justify left bottom)
				(hide yes)
			)
		)
		(property "Footprint" "antmicro-footprints:R_0402_1005Metric"
			(at 189.23 156.21 0)
			(effects
				(font
					(size 1.27 1.27)
					(thickness 0.15)
				)
				(justify left bottom)
				(hide yes)
			)
		)
		(property "Datasheet" "https://www.bourns.com/docs/product-datasheets/cr.pdf"
			(at 191.77 156.21 0)
			(effects
				(font
					(size 1.27 1.27)
					(thickness 0.15)
				)
				(justify left bottom)
				(hide yes)
			)
		)
		(property "Description" "SMD Chip Resistor, 1 kohm, ± 1%, 63 mW, 0402 [1005 Metric], Thick Film, General Purpose"
			(at 173.99 176.53 0)
			(effects
				(font
					(size 1.27 1.27)
				)
				(hide yes)
			)
		)
		(property "MPN" "CR0402-FX-1001GLF"
			(at 194.31 156.21 0)
			(effects
				(font
					(size 1.27 1.27)
					(thickness 0.15)
				)
				(justify left bottom)
				(hide yes)
			)
		)
		(property "Manufacturer" "Bourns"
			(at 196.85 156.21 0)
			(effects
				(font
					(size 1.27 1.27)
					(thickness 0.15)
				)
				(justify left bottom)
				(hide yes)
			)
		)
		(property "License" "Apache-2.0"
			(at 199.39 156.21 0)
			(effects
				(font
					(size 1.27 1.27)
					(thickness 0.15)
				)
				(justify left bottom)
				(hide yes)
			)
		)
		(property "Author" "Antmicro"
			(at 201.93 156.21 0)
			(effects
				(font
					(size 1.27 1.27)
					(thickness 0.15)
				)
				(justify left bottom)
				(hide yes)
			)
		)
		(property "Val" "1k"
			(at 175.514 175.26 90)
			(effects
				(font
					(size 1.27 1.27)
					(thickness 0.15)
				)
				(justify right)
			)
		)
		(property "Tolerance" "1%"
			(at 184.15 156.21 0)
			(effects
				(font
					(size 1.27 1.27)
				)
				(justify left bottom)
				(hide yes)
			)
		)
		(pin "2"
		)
		(pin "1"
		)
		(instances
			(project "OCuLink to 10GbE adapter"
				(path ""
					(reference "R143")
					(unit 1)
				)
			)
		)
	)
	(symbol
		(lib_id "antmicroResistors0402:R_100R_0402")
		(at 162.56 81.28 90)
		(unit 1)
		(exclude_from_sim no)
		(in_bom yes)
		(on_board yes)
		(dnp no)
		(property "Reference" "R139"
			(at 164.084 77.47 90)
			(effects
				(font
					(size 1.27 1.27)
					(thickness 0.15)
				)
				(justify right)
			)
		)
		(property "Value" "R_100R_0402"
			(at 175.26 60.96 0)
			(effects
				(font
					(size 1.27 1.27)
					(thickness 0.15)
				)
				(justify left bottom)
				(hide yes)
			)
		)
		(property "Footprint" "antmicro-footprints:R_0402_1005Metric"
			(at 177.8 60.96 0)
			(effects
				(font
					(size 1.27 1.27)
					(thickness 0.15)
				)
				(justify left bottom)
				(hide yes)
			)
		)
		(property "Datasheet" "https://www.bourns.com/docs/product-datasheets/cr.pdf"
			(at 180.34 60.96 0)
			(effects
				(font
					(size 1.27 1.27)
					(thickness 0.15)
				)
				(justify left bottom)
				(hide yes)
			)
		)
		(property "Description" "SMD Chip Resistor, 100 ohm, ± 1%, 62.5 mW, 0402 [1005 Metric], Thick Film, General Purpose"
			(at 162.56 81.28 0)
			(effects
				(font
					(size 1.27 1.27)
				)
				(hide yes)
			)
		)
		(property "MPN" "CR0402-FX-1000GLF"
			(at 182.88 60.96 0)
			(effects
				(font
					(size 1.27 1.27)
					(thickness 0.15)
				)
				(justify left bottom)
				(hide yes)
			)
		)
		(property "Manufacturer" "Bourns"
			(at 185.42 60.96 0)
			(effects
				(font
					(size 1.27 1.27)
					(thickness 0.15)
				)
				(justify left bottom)
				(hide yes)
			)
		)
		(property "License" "Apache-2.0"
			(at 187.96 60.96 0)
			(effects
				(font
					(size 1.27 1.27)
					(thickness 0.15)
				)
				(justify left bottom)
				(hide yes)
			)
		)
		(property "Author" "Antmicro"
			(at 190.5 60.96 0)
			(effects
				(font
					(size 1.27 1.27)
					(thickness 0.15)
				)
				(justify left bottom)
				(hide yes)
			)
		)
		(property "Val" "100R"
			(at 164.084 80.01 90)
			(effects
				(font
					(size 1.27 1.27)
					(thickness 0.15)
				)
				(justify right)
			)
		)
		(property "Tolerance" "1%"
			(at 172.72 60.96 0)
			(effects
				(font
					(size 1.27 1.27)
				)
				(justify left bottom)
				(hide yes)
			)
		)
		(pin "2"
		)
		(pin "1"
		)
		(instances
			(project "OCuLink to 10GbE adapter"
				(path ""
					(reference "R139")
					(unit 1)
				)
			)
		)
	)
	(symbol
		(lib_id "antmicropower:GND")
		(at 162.56 83.82 0)
		(unit 1)
		(exclude_from_sim no)
		(in_bom yes)
		(on_board yes)
		(dnp no)
		(property "Reference" "#PWR0298"
			(at 171.45 86.36 0)
			(effects
				(font
					(size 1.27 1.27)
					(thickness 0.15)
				)
				(justify left bottom)
				(hide yes)
			)
		)
		(property "Value" "GND"
			(at 162.56 87.63 0)
			(effects
				(font
					(size 1.27 1.27)
					(thickness 0.15)
				)
			)
		)
		(property "Footprint" ""
			(at 171.45 91.44 0)
			(effects
				(font
					(size 1.27 1.27)
					(thickness 0.15)
				)
				(justify left bottom)
				(hide yes)
			)
		)
		(property "Datasheet" ""
			(at 171.45 96.52 0)
			(effects
				(font
					(size 1.27 1.27)
					(thickness 0.15)
				)
				(justify left bottom)
				(hide yes)
			)
		)
		(property "Description" ""
			(at 162.56 83.82 0)
			(effects
				(font
					(size 1.27 1.27)
				)
				(hide yes)
			)
		)
		(property "Author" "Antmicro"
			(at 171.45 91.44 0)
			(effects
				(font
					(size 1.27 1.27)
					(thickness 0.15)
				)
				(justify left bottom)
				(hide yes)
			)
		)
		(property "License" "Apache-2.0"
			(at 171.45 93.98 0)
			(effects
				(font
					(size 1.27 1.27)
					(thickness 0.15)
				)
				(justify left bottom)
				(hide yes)
			)
		)
		(pin "1"
		)
		(instances
			(project "OCuLink to 10GbE adapter"
				(path ""
					(reference "#PWR0298")
					(unit 1)
				)
			)
		)
	)
	(symbol
		(lib_id "antmicropower:GND")
		(at 127 83.82 0)
		(unit 1)
		(exclude_from_sim no)
		(in_bom yes)
		(on_board yes)
		(dnp no)
		(property "Reference" "#PWR0294"
			(at 135.89 86.36 0)
			(effects
				(font
					(size 1.27 1.27)
					(thickness 0.15)
				)
				(justify left bottom)
				(hide yes)
			)
		)
		(property "Value" "GND"
			(at 127 87.63 0)
			(effects
				(font
					(size 1.27 1.27)
					(thickness 0.15)
				)
			)
		)
		(property "Footprint" ""
			(at 135.89 91.44 0)
			(effects
				(font
					(size 1.27 1.27)
					(thickness 0.15)
				)
				(justify left bottom)
				(hide yes)
			)
		)
		(property "Datasheet" ""
			(at 135.89 96.52 0)
			(effects
				(font
					(size 1.27 1.27)
					(thickness 0.15)
				)
				(justify left bottom)
				(hide yes)
			)
		)
		(property "Description" ""
			(at 127 83.82 0)
			(effects
				(font
					(size 1.27 1.27)
				)
				(hide yes)
			)
		)
		(property "Author" "Antmicro"
			(at 135.89 91.44 0)
			(effects
				(font
					(size 1.27 1.27)
					(thickness 0.15)
				)
				(justify left bottom)
				(hide yes)
			)
		)
		(property "License" "Apache-2.0"
			(at 135.89 93.98 0)
			(effects
				(font
					(size 1.27 1.27)
					(thickness 0.15)
				)
				(justify left bottom)
				(hide yes)
			)
		)
		(pin "1"
		)
		(instances
			(project "OCuLink to 10GbE adapter"
				(path ""
					(reference "#PWR0294")
					(unit 1)
				)
			)
		)
	)
	(symbol
		(lib_id "antmicroInterfaceControllers:EZX710AT2_S_LMR5")
		(at 195.58 49.53 0)
		(unit 5)
		(exclude_from_sim no)
		(in_bom yes)
		(on_board yes)
		(dnp no)
		(fields_autoplaced yes)
		(property "Reference" "U9"
			(at 220.98 41.91 0)
			(effects
				(font
					(size 1.27 1.27)
					(thickness 0.15)
				)
			)
		)
		(property "Value" "EZX710AT2_S_LMR5"
			(at 271.78 54.61 0)
			(effects
				(font
					(size 1.27 1.27)
					(thickness 0.15)
				)
				(justify left bottom)
				(hide yes)
			)
		)
		(property "Footprint" "antmicro-footprints:FCBGA-503_22x22mm_Layout21x24_P1mm"
			(at 271.78 57.15 0)
			(effects
				(font
					(size 1.27 1.27)
					(thickness 0.15)
				)
				(justify left bottom)
				(hide yes)
			)
		)
		(property "Datasheet" "https://www.google.com/url?sa=t&source=web&rct=j&opi=89978449&url=https://cdrdv2-public.intel.com/596333/596333_X710-TM4_Datasheet_v_2_4.pdf&ved=2ahUKEwiSuv20_sCOAxXVCRAIHdxGO_UQFnoECBEQAQ&usg=AOvVaw1CjGyrGWE8ZvOdw4VBsY6U"
			(at 271.78 59.69 0)
			(effects
				(font
					(size 1.27 1.27)
					(thickness 0.15)
				)
				(justify left bottom)
				(hide yes)
			)
		)
		(property "Description" "Ethernet ICs Intel Ethernet Controller 10 Gigabit X7"
			(at 271.78 62.23 0)
			(effects
				(font
					(size 1.27 1.27)
					(thickness 0.15)
				)
				(justify left bottom)
				(hide yes)
			)
		)
		(property "MPN" "EZX710AT2 S LMR5"
			(at 220.98 44.45 0)
			(effects
				(font
					(size 1.27 1.27)
					(thickness 0.15)
				)
			)
		)
		(property "Manufacturer" "Intel"
			(at 271.78 64.77 0)
			(effects
				(font
					(size 1.27 1.27)
					(thickness 0.15)
				)
				(justify left bottom)
				(hide yes)
			)
		)
		(property "Author" "Antmicro"
			(at 271.78 67.31 0)
			(effects
				(font
					(size 1.27 1.27)
					(thickness 0.15)
				)
				(justify left bottom)
				(hide yes)
			)
		)
		(property "License" "Apache-2.0"
			(at 271.78 69.85 0)
			(effects
				(font
					(size 1.27 1.27)
					(thickness 0.15)
				)
				(justify left bottom)
				(hide yes)
			)
		)
		(pin "B26"
		)
		(pin "E7"
		)
		(pin "G9"
		)
		(pin "E5"
		)
		(pin "A17"
		)
		(pin "J15"
		)
		(pin "P34"
		)
		(pin "AD30"
		)
		(pin "J7"
		)
		(pin "C1"
		)
		(pin "G37"
		)
		(pin "N37"
		)
		(pin "F38"
		)
		(pin "B2"
		)
		(pin "N29"
		)
		(pin "D4"
		)
		(pin "Y24"
		)
		(pin "N35"
		)
		(pin "C5"
		)
		(pin "V42"
		)
		(pin "M20"
		)
		(pin "P10"
		)
		(pin "L37"
		)
		(pin "B34"
		)
		(pin "U37"
		)
		(pin "AC7"
		)
		(pin "M4"
		)
		(pin "U35"
		)
		(pin "D18"
		)
		(pin "H16"
		)
		(pin "V30"
		)
		(pin "B38"
		)
		(pin "W29"
		)
		(pin "AB22"
		)
		(pin "AC15"
		)
		(pin "B28"
		)
		(pin "G3"
		)
		(pin "P32"
		)
		(pin "H14"
		)
		(pin "G13"
		)
		(pin "B30"
		)
		(pin "D22"
		)
		(pin "V10"
		)
		(pin "B24"
		)
		(pin "AD4"
		)
		(pin "AC5"
		)
		(pin "AA5"
		)
		(pin "V24"
		)
		(pin "V6"
		)
		(pin "D10"
		)
		(pin "AD20"
		)
		(pin "T26"
		)
		(pin "T10"
		)
		(pin "T12"
		)
		(pin "AD6"
		)
		(pin "H8"
		)
		(pin "H28"
		)
		(pin "N15"
		)
		(pin "AC29"
		)
		(pin "N17"
		)
		(pin "W31"
		)
		(pin "Y12"
		)
		(pin "W23"
		)
		(pin "AD32"
		)
		(pin "AB16"
		)
		(pin "T28"
		)
		(pin "D24"
		)
		(pin "D26"
		)
		(pin "G17"
		)
		(pin "K32"
		)
		(pin "F24"
		)
		(pin "F26"
		)
		(pin "J31"
		)
		(pin "T30"
		)
		(pin "AD34"
		)
		(pin "AA27"
		)
		(pin "R17"
		)
		(pin "W13"
		)
		(pin "M26"
		)
		(pin "C9"
		)
		(pin "AA41"
		)
		(pin "AC27"
		)
		(pin "K2"
		)
		(pin "AB20"
		)
		(pin "R7"
		)
		(pin "N39"
		)
		(pin "D6"
		)
		(pin "M22"
		)
		(pin "M2"
		)
		(pin "AC9"
		)
		(pin "A3"
		)
		(pin "P2"
		)
		(pin "AA33"
		)
		(pin "A23"
		)
		(pin "E35"
		)
		(pin "U3"
		)
		(pin "V36"
		)
		(pin "K42"
		)
		(pin "R41"
		)
		(pin "R1"
		)
		(pin "AD22"
		)
		(pin "W7"
		)
		(pin "AB18"
		)
		(pin "E19"
		)
		(pin "AB12"
		)
		(pin "AD28"
		)
		(pin "AD40"
		)
		(pin "J1"
		)
		(pin "Y6"
		)
		(pin "Y8"
		)
		(pin "H36"
		)
		(pin "C13"
		)
		(pin "C23"
		)
		(pin "Y38"
		)
		(pin "U21"
		)
		(pin "F32"
		)
		(pin "F34"
		)
		(pin "A25"
		)
		(pin "N23"
		)
		(pin "W41"
		)
		(pin "AC31"
		)
		(pin "D12"
		)
		(pin "K34"
		)
		(pin "AA23"
		)
		(pin "AC17"
		)
		(pin "V22"
		)
		(pin "AA39"
		)
		(pin "J41"
		)
		(pin "V14"
		)
		(pin "U23"
		)
		(pin "V16"
		)
		(pin "W35"
		)
		(pin "AC21"
		)
		(pin "D32"
		)
		(pin "L1"
		)
		(pin "P24"
		)
		(pin "J3"
		)
		(pin "AC41"
		)
		(pin "AD14"
		)
		(pin "K22"
		)
		(pin "A11"
		)
		(pin "AA15"
		)
		(pin "F2"
		)
		(pin "A9"
		)
		(pin "N27"
		)
		(pin "C19"
		)
		(pin "K30"
		)
		(pin "L23"
		)
		(pin "N41"
		)
		(pin "F20"
		)
		(pin "AB28"
		)
		(pin "AD12"
		)
		(pin "C21"
		)
		(pin "U9"
		)
		(pin "V20"
		)
		(pin "D20"
		)
		(pin "L21"
		)
		(pin "R15"
		)
		(pin "K4"
		)
		(pin "N1"
		)
		(pin "H12"
		)
		(pin "J23"
		)
		(pin "J5"
		)
		(pin "E9"
		)
		(pin "M28"
		)
		(pin "U1"
		)
		(pin "Y2"
		)
		(pin "G5"
		)
		(pin "K20"
		)
		(pin "M18"
		)
		(pin "V2"
		)
		(pin "AC39"
		)
		(pin "T32"
		)
		(pin "E25"
		)
		(pin "AD38"
		)
		(pin "H26"
		)
		(pin "AA31"
		)
		(pin "G31"
		)
		(pin "U27"
		)
		(pin "U17"
		)
		(pin "C11"
		)
		(pin "N3"
		)
		(pin "A37"
		)
		(pin "F6"
		)
		(pin "Y30"
		)
		(pin "U7"
		)
		(pin "G15"
		)
		(pin "C29"
		)
		(pin "E39"
		)
		(pin "A35"
		)
		(pin "L3"
		)
		(pin "N25"
		)
		(pin "R25"
		)
		(pin "J37"
		)
		(pin "H42"
		)
		(pin "AD24"
		)
		(pin "B14"
		)
		(pin "P6"
		)
		(pin "R31"
		)
		(pin "A5"
		)
		(pin "D14"
		)
		(pin "AB10"
		)
		(pin "B18"
		)
		(pin "A27"
		)
		(pin "T40"
		)
		(pin "AB40"
		)
		(pin "P4"
		)
		(pin "AA35"
		)
		(pin "F36"
		)
		(pin "K18"
		)
		(pin "K38"
		)
		(pin "N33"
		)
		(pin "Y26"
		)
		(pin "Y28"
		)
		(pin "G21"
		)
		(pin "AA1"
		)
		(pin "AB2"
		)
		(pin "V38"
		)
		(pin "J9"
		)
		(pin "B6"
		)
		(pin "L35"
		)
		(pin "N7"
		)
		(pin "AC1"
		)
		(pin "E23"
		)
		(pin "F40"
		)
		(pin "F42"
		)
		(pin "P36"
		)
		(pin "F4"
		)
		(pin "AD16"
		)
		(pin "R11"
		)
		(pin "R27"
		)
		(pin "J13"
		)
		(pin "V34"
		)
		(pin "M10"
		)
		(pin "Y4"
		)
		(pin "Y40"
		)
		(pin "L27"
		)
		(pin "L9"
		)
		(pin "K10"
		)
		(pin "L39"
		)
		(pin "U5"
		)
		(pin "AB42"
		)
		(pin "R5"
		)
		(pin "G23"
		)
		(pin "M8"
		)
		(pin "AD8"
		)
		(pin "M16"
		)
		(pin "M12"
		)
		(pin "E3"
		)
		(pin "B12"
		)
		(pin "R23"
		)
		(pin "W25"
		)
		(pin "H4"
		)
		(pin "F8"
		)
		(pin "AC23"
		)
		(pin "AA3"
		)
		(pin "B10"
		)
		(pin "E31"
		)
		(pin "E33"
		)
		(pin "G1"
		)
		(pin "F18"
		)
		(pin "W17"
		)
		(pin "K36"
		)
		(pin "AB26"
		)
		(pin "R13"
		)
		(pin "AB32"
		)
		(pin "V18"
		)
		(pin "D16"
		)
		(pin "AA37"
		)
		(pin "C31"
		)
		(pin "C41"
		)
		(pin "A41"
		)
		(pin "E1"
		)
		(pin "P38"
		)
		(pin "U19"
		)
		(pin "R29"
		)
		(pin "E37"
		)
		(pin "E29"
		)
		(pin "A21"
		)
		(pin "A31"
		)
		(pin "U29"
		)
		(pin "AB34"
		)
		(pin "E17"
		)
		(pin "W15"
		)
		(pin "H40"
		)
		(pin "M24"
		)
		(pin "U15"
		)
		(pin "H2"
		)
		(pin "N21"
		)
		(pin "W33"
		)
		(pin "J29"
		)
		(pin "T42"
		)
		(pin "A13"
		)
		(pin "AD26"
		)
		(pin "P28"
		)
		(pin "T24"
		)
		(pin "F12"
		)
		(pin "AD2"
		)
		(pin "H34"
		)
		(pin "J33"
		)
		(pin "P40"
		)
		(pin "C17"
		)
		(pin "W19"
		)
		(pin "M6"
		)
		(pin "H6"
		)
		(pin "M40"
		)
		(pin "D30"
		)
		(pin "F10"
		)
		(pin "Y14"
		)
		(pin "L29"
		)
		(pin "P22"
		)
		(pin "W1"
		)
		(pin "V28"
		)
		(pin "E11"
		)
		(pin "J25"
		)
		(pin "G27"
		)
		(pin "M34"
		)
		(pin "Y18"
		)
		(pin "K8"
		)
		(pin "AC35"
		)
		(pin "AD36"
		)
		(pin "G19"
		)
		(pin "G41"
		)
		(pin "W3"
		)
		(pin "C37"
		)
		(pin "C27"
		)
		(pin "Y22"
		)
		(pin "C35"
		)
		(pin "L41"
		)
		(pin "P30"
		)
		(pin "V8"
		)
		(pin "AB30"
		)
		(pin "A29"
		)
		(pin "B22"
		)
		(pin "B32"
		)
		(pin "T36"
		)
		(pin "AA17"
		)
		(pin "K12"
		)
		(pin "P8"
		)
		(pin "T22"
		)
		(pin "C15"
		)
		(pin "W9"
		)
		(pin "W11"
		)
		(pin "P42"
		)
		(pin "T6"
		)
		(pin "B40"
		)
		(pin "N9"
		)
		(pin "K6"
		)
		(pin "A33"
		)
		(pin "T38"
		)
		(pin "J35"
		)
		(pin "E41"
		)
		(pin "T2"
		)
		(pin "C3"
		)
		(pin "R3"
		)
		(pin "D8"
		)
		(pin "F28"
		)
		(pin "F30"
		)
		(pin "Y32"
		)
		(pin "Y36"
		)
		(pin "AC25"
		)
		(pin "T4"
		)
		(pin "V26"
		)
		(pin "B16"
		)
		(pin "V32"
		)
		(pin "H10"
		)
		(pin "A7"
		)
		(pin "R9"
		)
		(pin "N11"
		)
		(pin "R37"
		)
		(pin "W37"
		)
		(pin "V4"
		)
		(pin "T14"
		)
		(pin "T16"
		)
		(pin "J21"
		)
		(pin "AB14"
		)
		(pin "J17"
		)
		(pin "W5"
		)
		(pin "D34"
		)
		(pin "Y34"
		)
		(pin "M36"
		)
		(pin "AA25"
		)
		(pin "B4"
		)
		(pin "AA29"
		)
		(pin "K16"
		)
		(pin "V40"
		)
		(pin "AC37"
		)
		(pin "AB24"
		)
		(pin "AD18"
		)
		(pin "AA7"
		)
		(pin "V12"
		)
		(pin "AC13"
		)
		(pin "T8"
		)
		(pin "E21"
		)
		(pin "A19"
		)
		(pin "E27"
		)
		(pin "K14"
		)
		(pin "AA13"
		)
		(pin "P16"
		)
		(pin "P18"
		)
		(pin "H30"
		)
		(pin "N31"
		)
		(pin "P12"
		)
		(pin "P14"
		)
		(pin "B42"
		)
		(pin "G25"
		)
		(pin "U25"
		)
		(pin "A39"
		)
		(pin "J11"
		)
		(pin "G11"
		)
		(pin "G29"
		)
		(pin "R19"
		)
		(pin "AC11"
		)
		(pin "F22"
		)
		(pin "W39"
		)
		(pin "AA9"
		)
		(pin "AB38"
		)
		(pin "L31"
		)
		(pin "T34"
		)
		(pin "J39"
		)
		(pin "F14"
		)
		(pin "H24"
		)
		(pin "G35"
		)
		(pin "W21"
		)
		(pin "K40"
		)
		(pin "N19"
		)
		(pin "B20"
		)
		(pin "U31"
		)
		(pin "R21"
		)
		(pin "R39"
		)
		(pin "P20"
		)
		(pin "R35"
		)
		(pin "AD42"
		)
		(pin "K24"
		)
		(pin "AB4"
		)
		(pin "AC33"
		)
		(pin "B8"
		)
		(pin "U33"
		)
		(pin "H32"
		)
		(pin "L33"
		)
		(pin "J19"
		)
		(pin "U13"
		)
		(pin "C39"
		)
		(pin "H22"
		)
		(pin "AD10"
		)
		(pin "Y20"
		)
		(pin "E15"
		)
		(pin "AA21"
		)
		(pin "K26"
		)
		(pin "C25"
		)
		(pin "M42"
		)
		(pin "U41"
		)
		(pin "Y16"
		)
		(pin "D28"
		)
		(pin "D36"
		)
		(pin "Y10"
		)
		(pin "AC19"
		)
		(pin "AB8"
		)
		(pin "AB36"
		)
		(pin "P26"
		)
		(pin "D38"
		)
		(pin "D40"
		)
		(pin "AA19"
		)
		(pin "E13"
		)
		(pin "A15"
		)
		(pin "H20"
		)
		(pin "K28"
		)
		(pin "F16"
		)
		(pin "W27"
		)
		(pin "D42"
		)
		(pin "AB6"
		)
		(pin "M14"
		)
		(pin "M32"
		)
		(pin "N5"
		)
		(pin "U11"
		)
		(pin "J27"
		)
		(pin "M30"
		)
		(pin "C33"
		)
		(pin "C7"
		)
		(pin "L15"
		)
		(pin "G33"
		)
		(pin "L19"
		)
		(pin "L17"
		)
		(pin "L5"
		)
		(pin "L25"
		)
		(pin "M38"
		)
		(pin "T18"
		)
		(pin "T20"
		)
		(pin "H18"
		)
		(pin "G7"
		)
		(pin "B36"
		)
		(pin "U39"
		)
		(pin "G39"
		)
		(pin "D2"
		)
		(pin "R33"
		)
		(pin "L11"
		)
		(pin "AC3"
		)
		(pin "AA11"
		)
		(pin "H38"
		)
		(pin "N13"
		)
		(pin "L13"
		)
		(pin "L7"
		)
		(pin "Y42"
		)
		(instances
			(project ""
				(path ""
					(reference "U9")
					(unit 5)
				)
			)
		)
	)
	(symbol
		(lib_id "antmicropower:+1V8")
		(at 173.99 166.37 0)
		(unit 1)
		(exclude_from_sim no)
		(in_bom yes)
		(on_board yes)
		(dnp no)
		(property "Reference" "#PWR0301"
			(at 189.23 168.91 0)
			(effects
				(font
					(size 1.27 1.27)
					(thickness 0.15)
				)
				(justify left bottom)
				(hide yes)
			)
		)
		(property "Value" "+1V88"
			(at 173.99 162.56 0)
			(effects
				(font
					(size 1.27 1.27)
					(thickness 0.15)
				)
			)
		)
		(property "Footprint" ""
			(at 189.23 173.99 0)
			(effects
				(font
					(size 1.27 1.27)
					(thickness 0.15)
				)
				(justify left bottom)
				(hide yes)
			)
		)
		(property "Datasheet" ""
			(at 189.23 176.53 0)
			(effects
				(font
					(size 1.27 1.27)
					(thickness 0.15)
				)
				(justify left bottom)
				(hide yes)
			)
		)
		(property "Description" ""
			(at 173.99 166.37 0)
			(effects
				(font
					(size 1.27 1.27)
				)
				(hide yes)
			)
		)
		(property "Author" "Antmicro"
			(at 189.23 171.45 0)
			(effects
				(font
					(size 1.27 1.27)
					(thickness 0.15)
				)
				(justify left bottom)
				(hide yes)
			)
		)
		(property "License" "Apache-2.0"
			(at 189.23 173.99 0)
			(effects
				(font
					(size 1.27 1.27)
					(thickness 0.15)
				)
				(justify left bottom)
				(hide yes)
			)
		)
		(pin "1"
		)
		(instances
			(project "OCuLink to 10GbE adapter"
				(path ""
					(reference "#PWR0301")
					(unit 1)
				)
			)
		)
	)
	(symbol
		(lib_id "antmicropower:GND")
		(at 171.45 83.82 0)
		(unit 1)
		(exclude_from_sim no)
		(in_bom yes)
		(on_board yes)
		(dnp no)
		(property "Reference" "#PWR0299"
			(at 180.34 86.36 0)
			(effects
				(font
					(size 1.27 1.27)
					(thickness 0.15)
				)
				(justify left bottom)
				(hide yes)
			)
		)
		(property "Value" "GND"
			(at 171.45 87.63 0)
			(effects
				(font
					(size 1.27 1.27)
					(thickness 0.15)
				)
			)
		)
		(property "Footprint" ""
			(at 180.34 91.44 0)
			(effects
				(font
					(size 1.27 1.27)
					(thickness 0.15)
				)
				(justify left bottom)
				(hide yes)
			)
		)
		(property "Datasheet" ""
			(at 180.34 96.52 0)
			(effects
				(font
					(size 1.27 1.27)
					(thickness 0.15)
				)
				(justify left bottom)
				(hide yes)
			)
		)
		(property "Description" ""
			(at 171.45 83.82 0)
			(effects
				(font
					(size 1.27 1.27)
				)
				(hide yes)
			)
		)
		(property "Author" "Antmicro"
			(at 180.34 91.44 0)
			(effects
				(font
					(size 1.27 1.27)
					(thickness 0.15)
				)
				(justify left bottom)
				(hide yes)
			)
		)
		(property "License" "Apache-2.0"
			(at 180.34 93.98 0)
			(effects
				(font
					(size 1.27 1.27)
					(thickness 0.15)
				)
				(justify left bottom)
				(hide yes)
			)
		)
		(pin "1"
		)
		(instances
			(project "OCuLink to 10GbE adapter"
				(path ""
					(reference "#PWR0299")
					(unit 1)
				)
			)
		)
	)
	(symbol
		(lib_id "antmicroResistors0402:R_100R_0402")
		(at 135.89 81.28 90)
		(unit 1)
		(exclude_from_sim no)
		(in_bom yes)
		(on_board yes)
		(dnp no)
		(property "Reference" "R136"
			(at 137.414 77.47 90)
			(effects
				(font
					(size 1.27 1.27)
					(thickness 0.15)
				)
				(justify right)
			)
		)
		(property "Value" "R_100R_0402"
			(at 148.59 60.96 0)
			(effects
				(font
					(size 1.27 1.27)
					(thickness 0.15)
				)
				(justify left bottom)
				(hide yes)
			)
		)
		(property "Footprint" "antmicro-footprints:R_0402_1005Metric"
			(at 151.13 60.96 0)
			(effects
				(font
					(size 1.27 1.27)
					(thickness 0.15)
				)
				(justify left bottom)
				(hide yes)
			)
		)
		(property "Datasheet" "https://www.bourns.com/docs/product-datasheets/cr.pdf"
			(at 153.67 60.96 0)
			(effects
				(font
					(size 1.27 1.27)
					(thickness 0.15)
				)
				(justify left bottom)
				(hide yes)
			)
		)
		(property "Description" "SMD Chip Resistor, 100 ohm, ± 1%, 62.5 mW, 0402 [1005 Metric], Thick Film, General Purpose"
			(at 135.89 81.28 0)
			(effects
				(font
					(size 1.27 1.27)
				)
				(hide yes)
			)
		)
		(property "MPN" "CR0402-FX-1000GLF"
			(at 156.21 60.96 0)
			(effects
				(font
					(size 1.27 1.27)
					(thickness 0.15)
				)
				(justify left bottom)
				(hide yes)
			)
		)
		(property "Manufacturer" "Bourns"
			(at 158.75 60.96 0)
			(effects
				(font
					(size 1.27 1.27)
					(thickness 0.15)
				)
				(justify left bottom)
				(hide yes)
			)
		)
		(property "License" "Apache-2.0"
			(at 161.29 60.96 0)
			(effects
				(font
					(size 1.27 1.27)
					(thickness 0.15)
				)
				(justify left bottom)
				(hide yes)
			)
		)
		(property "Author" "Antmicro"
			(at 163.83 60.96 0)
			(effects
				(font
					(size 1.27 1.27)
					(thickness 0.15)
				)
				(justify left bottom)
				(hide yes)
			)
		)
		(property "Val" "100R"
			(at 137.414 80.01 90)
			(effects
				(font
					(size 1.27 1.27)
					(thickness 0.15)
				)
				(justify right)
			)
		)
		(property "Tolerance" "1%"
			(at 146.05 60.96 0)
			(effects
				(font
					(size 1.27 1.27)
				)
				(justify left bottom)
				(hide yes)
			)
		)
		(pin "2"
		)
		(pin "1"
		)
		(instances
			(project "OCuLink to 10GbE adapter"
				(path ""
					(reference "R136")
					(unit 1)
				)
			)
		)
	)
	(symbol
		(lib_id "antmicroResistors0402:R_10k_0402")
		(at 269.24 62.23 90)
		(unit 1)
		(exclude_from_sim no)
		(in_bom yes)
		(on_board yes)
		(dnp no)
		(property "Reference" "R132"
			(at 270.764 58.42 90)
			(effects
				(font
					(size 1.27 1.27)
					(thickness 0.15)
				)
				(justify right)
			)
		)
		(property "Value" "R_10k_0402"
			(at 281.94 41.91 0)
			(effects
				(font
					(size 1.27 1.27)
					(thickness 0.15)
				)
				(justify left bottom)
				(hide yes)
			)
		)
		(property "Footprint" "antmicro-footprints:R_0402_1005Metric"
			(at 284.48 41.91 0)
			(effects
				(font
					(size 1.27 1.27)
					(thickness 0.15)
				)
				(justify left bottom)
				(hide yes)
			)
		)
		(property "Datasheet" "https://www.bourns.com/docs/product-datasheets/cr.pdf"
			(at 287.02 41.91 0)
			(effects
				(font
					(size 1.27 1.27)
					(thickness 0.15)
				)
				(justify left bottom)
				(hide yes)
			)
		)
		(property "Description" "SMD Chip Resistor, 10 kohm, ± 1%, 62.5 mW, 0402 [1005 Metric], Thick Film, General Purpose"
			(at 269.24 62.23 0)
			(effects
				(font
					(size 1.27 1.27)
				)
				(hide yes)
			)
		)
		(property "MPN" "CR0402-FX-1002GLF"
			(at 289.56 41.91 0)
			(effects
				(font
					(size 1.27 1.27)
					(thickness 0.15)
				)
				(justify left bottom)
				(hide yes)
			)
		)
		(property "Manufacturer" "Bourns"
			(at 292.1 41.91 0)
			(effects
				(font
					(size 1.27 1.27)
					(thickness 0.15)
				)
				(justify left bottom)
				(hide yes)
			)
		)
		(property "License" "Apache-2.0"
			(at 294.64 41.91 0)
			(effects
				(font
					(size 1.27 1.27)
					(thickness 0.15)
				)
				(justify left bottom)
				(hide yes)
			)
		)
		(property "Author" "Antmicro"
			(at 297.18 41.91 0)
			(effects
				(font
					(size 1.27 1.27)
					(thickness 0.15)
				)
				(justify left bottom)
				(hide yes)
			)
		)
		(property "Val" "10k"
			(at 270.764 60.96 90)
			(effects
				(font
					(size 1.27 1.27)
					(thickness 0.15)
				)
				(justify right)
			)
		)
		(property "Tolerance" "1%"
			(at 279.4 41.91 0)
			(effects
				(font
					(size 1.27 1.27)
				)
				(justify left bottom)
				(hide yes)
			)
		)
		(pin "1"
		)
		(pin "2"
		)
		(instances
			(project "OCuLink to 10GbE adapter"
				(path ""
					(reference "R132")
					(unit 1)
				)
			)
		)
	)
	(symbol
		(lib_id "antmicroResistors0402:R_100R_0402")
		(at 153.67 81.28 90)
		(unit 1)
		(exclude_from_sim no)
		(in_bom yes)
		(on_board yes)
		(dnp no)
		(property "Reference" "R138"
			(at 155.194 77.47 90)
			(effects
				(font
					(size 1.27 1.27)
					(thickness 0.15)
				)
				(justify right)
			)
		)
		(property "Value" "R_100R_0402"
			(at 166.37 60.96 0)
			(effects
				(font
					(size 1.27 1.27)
					(thickness 0.15)
				)
				(justify left bottom)
				(hide yes)
			)
		)
		(property "Footprint" "antmicro-footprints:R_0402_1005Metric"
			(at 168.91 60.96 0)
			(effects
				(font
					(size 1.27 1.27)
					(thickness 0.15)
				)
				(justify left bottom)
				(hide yes)
			)
		)
		(property "Datasheet" "https://www.bourns.com/docs/product-datasheets/cr.pdf"
			(at 171.45 60.96 0)
			(effects
				(font
					(size 1.27 1.27)
					(thickness 0.15)
				)
				(justify left bottom)
				(hide yes)
			)
		)
		(property "Description" "SMD Chip Resistor, 100 ohm, ± 1%, 62.5 mW, 0402 [1005 Metric], Thick Film, General Purpose"
			(at 153.67 81.28 0)
			(effects
				(font
					(size 1.27 1.27)
				)
				(hide yes)
			)
		)
		(property "MPN" "CR0402-FX-1000GLF"
			(at 173.99 60.96 0)
			(effects
				(font
					(size 1.27 1.27)
					(thickness 0.15)
				)
				(justify left bottom)
				(hide yes)
			)
		)
		(property "Manufacturer" "Bourns"
			(at 176.53 60.96 0)
			(effects
				(font
					(size 1.27 1.27)
					(thickness 0.15)
				)
				(justify left bottom)
				(hide yes)
			)
		)
		(property "License" "Apache-2.0"
			(at 179.07 60.96 0)
			(effects
				(font
					(size 1.27 1.27)
					(thickness 0.15)
				)
				(justify left bottom)
				(hide yes)
			)
		)
		(property "Author" "Antmicro"
			(at 181.61 60.96 0)
			(effects
				(font
					(size 1.27 1.27)
					(thickness 0.15)
				)
				(justify left bottom)
				(hide yes)
			)
		)
		(property "Val" "100R"
			(at 155.194 80.01 90)
			(effects
				(font
					(size 1.27 1.27)
					(thickness 0.15)
				)
				(justify right)
			)
		)
		(property "Tolerance" "1%"
			(at 163.83 60.96 0)
			(effects
				(font
					(size 1.27 1.27)
				)
				(justify left bottom)
				(hide yes)
			)
		)
		(pin "2"
		)
		(pin "1"
		)
		(instances
			(project "OCuLink to 10GbE adapter"
				(path ""
					(reference "R138")
					(unit 1)
				)
			)
		)
	)
	(symbol
		(lib_id "antmicropower:+3V3")
		(at 276.86 21.59 0)
		(unit 1)
		(exclude_from_sim no)
		(in_bom yes)
		(on_board yes)
		(dnp no)
		(property "Reference" "#PWR0289"
			(at 292.1 21.59 0)
			(effects
				(font
					(size 1.27 1.27)
					(thickness 0.15)
				)
				(justify left bottom)
				(hide yes)
			)
		)
		(property "Value" "+3V3"
			(at 276.86 17.78 0)
			(effects
				(font
					(size 1.27 1.27)
					(thickness 0.15)
				)
			)
		)
		(property "Footprint" ""
			(at 292.1 29.21 0)
			(effects
				(font
					(size 1.27 1.27)
					(thickness 0.15)
				)
				(justify left bottom)
				(hide yes)
			)
		)
		(property "Datasheet" ""
			(at 292.1 31.75 0)
			(effects
				(font
					(size 1.27 1.27)
					(thickness 0.15)
				)
				(justify left bottom)
				(hide yes)
			)
		)
		(property "Description" ""
			(at 276.86 21.59 0)
			(effects
				(font
					(size 1.27 1.27)
				)
				(hide yes)
			)
		)
		(property "Author" "Antmicro"
			(at 292.1 24.13 0)
			(effects
				(font
					(size 1.27 1.27)
					(thickness 0.15)
				)
				(justify left bottom)
				(hide yes)
			)
		)
		(property "License" "Apache-2.0"
			(at 292.1 26.67 0)
			(effects
				(font
					(size 1.27 1.27)
					(thickness 0.15)
				)
				(justify left bottom)
				(hide yes)
			)
		)
		(pin "1"
		)
		(instances
			(project "OCuLink to 10GbE adapter"
				(path ""
					(reference "#PWR0289")
					(unit 1)
				)
			)
		)
	)
	(symbol
		(lib_id "antmicroSlideSwitches:SW_DS04-254-1-01BK-SMT")
		(at 276.86 36.83 90)
		(unit 1)
		(exclude_from_sim no)
		(in_bom yes)
		(on_board yes)
		(dnp no)
		(fields_autoplaced yes)
		(property "Reference" "SW1"
			(at 280.67 29.21 90)
			(effects
				(font
					(size 1.27 1.27)
					(thickness 0.15)
				)
				(justify right)
			)
		)
		(property "Value" "SW_DS04-254-1-01BK-SMT"
			(at 280.67 31.75 90)
			(effects
				(font
					(size 1.27 1.27)
					(thickness 0.15)
				)
				(justify right)
				(hide yes)
			)
		)
		(property "Footprint" "antmicro-footprints:SW_DS04-254-1-01BK-SMT"
			(at 284.48 10.16 0)
			(effects
				(font
					(size 1.27 1.27)
					(thickness 0.15)
				)
				(justify left bottom)
				(hide yes)
			)
		)
		(property "Datasheet" "https://www.mouser.com/datasheet/2/670/ds04_254_smt-1777718.pdf"
			(at 287.02 10.16 0)
			(effects
				(font
					(size 1.27 1.27)
					(thickness 0.15)
				)
				(justify left bottom)
				(hide yes)
			)
		)
		(property "Description" "Slide switch"
			(at 299.72 10.16 0)
			(effects
				(font
					(size 1.27 1.27)
				)
				(justify left bottom)
				(hide yes)
			)
		)
		(property "MPN" "DS04-254-1-01BK-SMT"
			(at 280.67 31.75 90)
			(effects
				(font
					(size 1.27 1.27)
					(thickness 0.15)
				)
				(justify right)
			)
		)
		(property "Manufacturer" "CUI Inc"
			(at 292.1 10.16 0)
			(effects
				(font
					(size 1.27 1.27)
					(thickness 0.15)
				)
				(justify left bottom)
				(hide yes)
			)
		)
		(property "Author" "Antmicro"
			(at 294.64 10.16 0)
			(effects
				(font
					(size 1.27 1.27)
					(thickness 0.15)
				)
				(justify left bottom)
				(hide yes)
			)
		)
		(property "License" "Apache-2.0"
			(at 297.18 10.16 0)
			(effects
				(font
					(size 1.27 1.27)
					(thickness 0.15)
				)
				(justify left bottom)
				(hide yes)
			)
		)
		(pin "2"
		)
		(pin "1"
		)
		(instances
			(project "oculink-to-10gbe-adapter"
				(path ""
					(reference "SW1")
					(unit 1)
				)
			)
		)
	)
	(symbol
		(lib_id "antmicropower:GND")
		(at 144.78 83.82 0)
		(unit 1)
		(exclude_from_sim no)
		(in_bom yes)
		(on_board yes)
		(dnp no)
		(property "Reference" "#PWR0296"
			(at 153.67 86.36 0)
			(effects
				(font
					(size 1.27 1.27)
					(thickness 0.15)
				)
				(justify left bottom)
				(hide yes)
			)
		)
		(property "Value" "GND"
			(at 144.78 87.63 0)
			(effects
				(font
					(size 1.27 1.27)
					(thickness 0.15)
				)
			)
		)
		(property "Footprint" ""
			(at 153.67 91.44 0)
			(effects
				(font
					(size 1.27 1.27)
					(thickness 0.15)
				)
				(justify left bottom)
				(hide yes)
			)
		)
		(property "Datasheet" ""
			(at 153.67 96.52 0)
			(effects
				(font
					(size 1.27 1.27)
					(thickness 0.15)
				)
				(justify left bottom)
				(hide yes)
			)
		)
		(property "Description" ""
			(at 144.78 83.82 0)
			(effects
				(font
					(size 1.27 1.27)
				)
				(hide yes)
			)
		)
		(property "Author" "Antmicro"
			(at 153.67 91.44 0)
			(effects
				(font
					(size 1.27 1.27)
					(thickness 0.15)
				)
				(justify left bottom)
				(hide yes)
			)
		)
		(property "License" "Apache-2.0"
			(at 153.67 93.98 0)
			(effects
				(font
					(size 1.27 1.27)
					(thickness 0.15)
				)
				(justify left bottom)
				(hide yes)
			)
		)
		(pin "1"
		)
		(instances
			(project "OCuLink to 10GbE adapter"
				(path ""
					(reference "#PWR0296")
					(unit 1)
				)
			)
		)
	)
	(symbol
		(lib_id "antmicropower:GND")
		(at 193.04 250.19 0)
		(unit 1)
		(exclude_from_sim no)
		(in_bom yes)
		(on_board yes)
		(dnp no)
		(property "Reference" "#PWR0316"
			(at 201.93 252.73 0)
			(effects
				(font
					(size 1.27 1.27)
					(thickness 0.15)
				)
				(justify left bottom)
				(hide yes)
			)
		)
		(property "Value" "GND"
			(at 193.04 254 0)
			(effects
				(font
					(size 1.27 1.27)
					(thickness 0.15)
				)
			)
		)
		(property "Footprint" ""
			(at 201.93 257.81 0)
			(effects
				(font
					(size 1.27 1.27)
					(thickness 0.15)
				)
				(justify left bottom)
				(hide yes)
			)
		)
		(property "Datasheet" ""
			(at 201.93 262.89 0)
			(effects
				(font
					(size 1.27 1.27)
					(thickness 0.15)
				)
				(justify left bottom)
				(hide yes)
			)
		)
		(property "Description" ""
			(at 193.04 250.19 0)
			(effects
				(font
					(size 1.27 1.27)
				)
				(hide yes)
			)
		)
		(property "Author" "Antmicro"
			(at 201.93 257.81 0)
			(effects
				(font
					(size 1.27 1.27)
					(thickness 0.15)
				)
				(justify left bottom)
				(hide yes)
			)
		)
		(property "License" "Apache-2.0"
			(at 201.93 260.35 0)
			(effects
				(font
					(size 1.27 1.27)
					(thickness 0.15)
				)
				(justify left bottom)
				(hide yes)
			)
		)
		(pin "1"
		)
		(instances
			(project "OCuLink to 10GbE adapter"
				(path ""
					(reference "#PWR0316")
					(unit 1)
				)
			)
		)
	)
	(symbol
		(lib_id "antmicroResistors0402:R_1k_0402")
		(at 276.86 46.99 90)
		(unit 1)
		(exclude_from_sim no)
		(in_bom yes)
		(on_board yes)
		(dnp no)
		(property "Reference" "R130"
			(at 278.384 43.18 90)
			(effects
				(font
					(size 1.27 1.27)
					(thickness 0.15)
				)
				(justify right)
			)
		)
		(property "Value" "R_1k_0402"
			(at 289.56 26.67 0)
			(effects
				(font
					(size 1.27 1.27)
					(thickness 0.15)
				)
				(justify left bottom)
				(hide yes)
			)
		)
		(property "Footprint" "antmicro-footprints:R_0402_1005Metric"
			(at 292.1 26.67 0)
			(effects
				(font
					(size 1.27 1.27)
					(thickness 0.15)
				)
				(justify left bottom)
				(hide yes)
			)
		)
		(property "Datasheet" "https://www.bourns.com/docs/product-datasheets/cr.pdf"
			(at 294.64 26.67 0)
			(effects
				(font
					(size 1.27 1.27)
					(thickness 0.15)
				)
				(justify left bottom)
				(hide yes)
			)
		)
		(property "Description" "SMD Chip Resistor, 1 kohm, ± 1%, 63 mW, 0402 [1005 Metric], Thick Film, General Purpose"
			(at 276.86 46.99 0)
			(effects
				(font
					(size 1.27 1.27)
				)
				(hide yes)
			)
		)
		(property "MPN" "CR0402-FX-1001GLF"
			(at 297.18 26.67 0)
			(effects
				(font
					(size 1.27 1.27)
					(thickness 0.15)
				)
				(justify left bottom)
				(hide yes)
			)
		)
		(property "Manufacturer" "Bourns"
			(at 299.72 26.67 0)
			(effects
				(font
					(size 1.27 1.27)
					(thickness 0.15)
				)
				(justify left bottom)
				(hide yes)
			)
		)
		(property "License" "Apache-2.0"
			(at 302.26 26.67 0)
			(effects
				(font
					(size 1.27 1.27)
					(thickness 0.15)
				)
				(justify left bottom)
				(hide yes)
			)
		)
		(property "Author" "Antmicro"
			(at 304.8 26.67 0)
			(effects
				(font
					(size 1.27 1.27)
					(thickness 0.15)
				)
				(justify left bottom)
				(hide yes)
			)
		)
		(property "Val" "1k"
			(at 278.384 45.72 90)
			(effects
				(font
					(size 1.27 1.27)
					(thickness 0.15)
				)
				(justify right)
			)
		)
		(property "Tolerance" "1%"
			(at 287.02 26.67 0)
			(effects
				(font
					(size 1.27 1.27)
				)
				(justify left bottom)
				(hide yes)
			)
		)
		(pin "2"
		)
		(pin "1"
		)
		(instances
			(project "OCuLink to 10GbE adapter"
				(path ""
					(reference "R130")
					(unit 1)
				)
			)
		)
	)
)
